FILE_TYPE = MACRO_DRAWING;
SET COLOR_WIRE YELLOW;
SET COLOR_PROP MONO;
SET COLOR_DOT WHITE;
SET COLOR_ARC YELLOW;
SET COLOR_BODY GREEN;
SET COLOR_NOTE MONO;
SET PROP_DISPLAY VALUE;
SET PAGE_NUMBER P34;
FORCEADD OFFPAGE..1
(-6500 2575);
FORCEPROP 2 LAST $XR0 68 
J 0
(-6751 2575);
DISPLAY 0.638298 (-6751 2575);
PAINT MONO (-6751 2575);
FORCEPROP 2 LAST CDS_LIB mstr_standard
J 0
(-6500 2575);
PAINT MONO (-6500 2575);
DISPLAY INVISIBLE (-6500 2575);
FORCEPROP 1 LAST OFFPAGE TRUE
J 0
(-6175 2450);
DISPLAY 1.170213 (-6175 2450);
PAINT GREEN (-6175 2450);
DISPLAY INVISIBLE (-6175 2450);
FORCEPROP 1 LAST COMMENT_BODY TRUE
J 0
(-6375 2475);
DISPLAY 1.170213 (-6375 2475);
PAINT GREEN (-6375 2475);
DISPLAY INVISIBLE (-6375 2475);
FORCEPROP 2 LAST PATH I1
J 0
(-6450 2650);
DISPLAY 1.021277 (-6450 2650);
PAINT ORANGE (-6450 2650);
DISPLAY INVISIBLE (-6450 2650);
FORCEADD TAP..1
R 2
(-5300 1925);
FORCEPROP 3 LASTPIN (-5250 1925) SIG_NAME UPI_CPU1_CPU0_P1P1_DN<12>
J 0
(-5240 1935);
DISPLAY 0.659574 (-5240 1935);
PAINT MONO (-5240 1935);
DISPLAY INVISIBLE (-5240 1935);
FORCEPROP 1 LASTPIN (-5250 1925) BN 12
J 2
(-5238 1933);
DISPLAY 0.617021 (-5238 1933);
PAINT PINK (-5238 1933);
FORCEPROP 2 LAST CDS_LIB mstr_standard
J 0
(-5300 1925);
PAINT MONO (-5300 1925);
DISPLAY INVISIBLE (-5300 1925);
FORCEPROP 1 LAST BODY_TYPE PLUMBING
J 2
(-5300 1975);
DISPLAY 1.446809 (-5300 1975);
PAINT GREEN (-5300 1975);
DISPLAY INVISIBLE (-5300 1975);
FORCEPROP 1 LAST HDL_TAP TRUE
J 2
(-5625 1800);
DISPLAY 1.446809 (-5625 1800);
PAINT GREEN (-5625 1800);
DISPLAY INVISIBLE (-5625 1800);
FORCEPROP 1 LAST PATH I10
J 2
(-5298 1925);
DISPLAY 0.872340 (-5298 1925);
PAINT GREEN (-5298 1925);
DISPLAY INVISIBLE (-5298 1925);
FORCEADD TAP..1
R 2
(-5300 1825);
FORCEPROP 3 LASTPIN (-5250 1825) SIG_NAME UPI_CPU1_CPU0_P1P1_DN<14>
J 0
(-5240 1835);
DISPLAY 0.659574 (-5240 1835);
PAINT MONO (-5240 1835);
DISPLAY INVISIBLE (-5240 1835);
FORCEPROP 1 LASTPIN (-5250 1825) BN 14
J 2
(-5238 1833);
DISPLAY 0.617021 (-5238 1833);
PAINT PINK (-5238 1833);
FORCEPROP 2 LAST CDS_LIB mstr_standard
J 0
(-5300 1825);
PAINT MONO (-5300 1825);
DISPLAY INVISIBLE (-5300 1825);
FORCEPROP 1 LAST BODY_TYPE PLUMBING
J 2
(-5300 1875);
DISPLAY 1.446809 (-5300 1875);
PAINT GREEN (-5300 1875);
DISPLAY INVISIBLE (-5300 1875);
FORCEPROP 1 LAST HDL_TAP TRUE
J 2
(-5625 1700);
DISPLAY 1.446809 (-5625 1700);
PAINT GREEN (-5625 1700);
DISPLAY INVISIBLE (-5625 1700);
FORCEPROP 1 LAST PATH I11
J 2
(-5298 1825);
DISPLAY 0.872340 (-5298 1825);
PAINT GREEN (-5298 1825);
DISPLAY INVISIBLE (-5298 1825);
FORCEADD TAP..1
R 2
(-5300 1975);
FORCEPROP 3 LASTPIN (-5250 1975) SIG_NAME UPI_CPU1_CPU0_P1P1_DN<11>
J 0
(-5240 1985);
DISPLAY 0.659574 (-5240 1985);
PAINT MONO (-5240 1985);
DISPLAY INVISIBLE (-5240 1985);
FORCEPROP 1 LASTPIN (-5250 1975) BN 11
J 2
(-5238 1983);
DISPLAY 0.617021 (-5238 1983);
PAINT PINK (-5238 1983);
FORCEPROP 2 LAST CDS_LIB mstr_standard
J 0
(-5300 1975);
PAINT MONO (-5300 1975);
DISPLAY INVISIBLE (-5300 1975);
FORCEPROP 1 LAST BODY_TYPE PLUMBING
J 2
(-5300 2025);
DISPLAY 1.446809 (-5300 2025);
PAINT GREEN (-5300 2025);
DISPLAY INVISIBLE (-5300 2025);
FORCEPROP 1 LAST HDL_TAP TRUE
J 2
(-5625 1850);
DISPLAY 1.446809 (-5625 1850);
PAINT GREEN (-5625 1850);
DISPLAY INVISIBLE (-5625 1850);
FORCEPROP 1 LAST PATH I12
J 2
(-5298 1975);
DISPLAY 0.872340 (-5298 1975);
PAINT GREEN (-5298 1975);
DISPLAY INVISIBLE (-5298 1975);
FORCEADD TAP..1
R 2
(-5300 2025);
FORCEPROP 3 LASTPIN (-5250 2025) SIG_NAME UPI_CPU1_CPU0_P1P1_DN<10>
J 0
(-5240 2035);
DISPLAY 0.659574 (-5240 2035);
PAINT MONO (-5240 2035);
DISPLAY INVISIBLE (-5240 2035);
FORCEPROP 1 LASTPIN (-5250 2025) BN 10
J 2
(-5238 2033);
DISPLAY 0.617021 (-5238 2033);
PAINT PINK (-5238 2033);
FORCEPROP 2 LAST CDS_LIB mstr_standard
J 0
(-5300 2025);
PAINT MONO (-5300 2025);
DISPLAY INVISIBLE (-5300 2025);
FORCEPROP 1 LAST BODY_TYPE PLUMBING
J 2
(-5300 2075);
DISPLAY 1.446809 (-5300 2075);
PAINT GREEN (-5300 2075);
DISPLAY INVISIBLE (-5300 2075);
FORCEPROP 1 LAST HDL_TAP TRUE
J 2
(-5625 1900);
DISPLAY 1.446809 (-5625 1900);
PAINT GREEN (-5625 1900);
DISPLAY INVISIBLE (-5625 1900);
FORCEPROP 1 LAST PATH I13
J 2
(-5298 2025);
DISPLAY 0.872340 (-5298 2025);
PAINT GREEN (-5298 2025);
DISPLAY INVISIBLE (-5298 2025);
FORCEADD TAP..1
R 2
(-5300 2075);
FORCEPROP 3 LASTPIN (-5250 2075) SIG_NAME UPI_CPU1_CPU0_P1P1_DN<9>
J 0
(-5240 2085);
DISPLAY 0.659574 (-5240 2085);
PAINT MONO (-5240 2085);
DISPLAY INVISIBLE (-5240 2085);
FORCEPROP 1 LASTPIN (-5250 2075) BN 9
J 2
(-5238 2083);
DISPLAY 0.617021 (-5238 2083);
PAINT PINK (-5238 2083);
FORCEPROP 2 LAST CDS_LIB mstr_standard
J 0
(-5300 2075);
PAINT MONO (-5300 2075);
DISPLAY INVISIBLE (-5300 2075);
FORCEPROP 1 LAST BODY_TYPE PLUMBING
J 2
(-5300 2125);
DISPLAY 1.446809 (-5300 2125);
PAINT GREEN (-5300 2125);
DISPLAY INVISIBLE (-5300 2125);
FORCEPROP 1 LAST HDL_TAP TRUE
J 2
(-5625 1950);
DISPLAY 1.446809 (-5625 1950);
PAINT GREEN (-5625 1950);
DISPLAY INVISIBLE (-5625 1950);
FORCEPROP 1 LAST PATH I14
J 2
(-5298 2075);
DISPLAY 0.872340 (-5298 2075);
PAINT GREEN (-5298 2075);
DISPLAY INVISIBLE (-5298 2075);
FORCEADD TAP..1
R 2
(-5300 2125);
FORCEPROP 3 LASTPIN (-5250 2125) SIG_NAME UPI_CPU1_CPU0_P1P1_DN<8>
J 0
(-5240 2135);
DISPLAY 0.659574 (-5240 2135);
PAINT MONO (-5240 2135);
DISPLAY INVISIBLE (-5240 2135);
FORCEPROP 1 LASTPIN (-5250 2125) BN 8
J 2
(-5238 2133);
DISPLAY 0.617021 (-5238 2133);
PAINT PINK (-5238 2133);
FORCEPROP 2 LAST CDS_LIB mstr_standard
J 0
(-5300 2125);
PAINT MONO (-5300 2125);
DISPLAY INVISIBLE (-5300 2125);
FORCEPROP 1 LAST BODY_TYPE PLUMBING
J 2
(-5300 2175);
DISPLAY 1.446809 (-5300 2175);
PAINT GREEN (-5300 2175);
DISPLAY INVISIBLE (-5300 2175);
FORCEPROP 1 LAST HDL_TAP TRUE
J 2
(-5625 2000);
DISPLAY 1.446809 (-5625 2000);
PAINT GREEN (-5625 2000);
DISPLAY INVISIBLE (-5625 2000);
FORCEPROP 1 LAST PATH I15
J 2
(-5298 2125);
DISPLAY 0.872340 (-5298 2125);
PAINT GREEN (-5298 2125);
DISPLAY INVISIBLE (-5298 2125);
FORCEADD TAP..1
R 2
(-5300 2175);
FORCEPROP 3 LASTPIN (-5250 2175) SIG_NAME UPI_CPU1_CPU0_P1P1_DN<7>
J 0
(-5240 2185);
DISPLAY 0.659574 (-5240 2185);
PAINT MONO (-5240 2185);
DISPLAY INVISIBLE (-5240 2185);
FORCEPROP 1 LASTPIN (-5250 2175) BN 7
J 2
(-5238 2183);
DISPLAY 0.617021 (-5238 2183);
PAINT PINK (-5238 2183);
FORCEPROP 2 LAST CDS_LIB mstr_standard
J 0
(-5300 2175);
PAINT MONO (-5300 2175);
DISPLAY INVISIBLE (-5300 2175);
FORCEPROP 1 LAST BODY_TYPE PLUMBING
J 2
(-5300 2225);
DISPLAY 1.446809 (-5300 2225);
PAINT GREEN (-5300 2225);
DISPLAY INVISIBLE (-5300 2225);
FORCEPROP 1 LAST HDL_TAP TRUE
J 2
(-5625 2050);
DISPLAY 1.446809 (-5625 2050);
PAINT GREEN (-5625 2050);
DISPLAY INVISIBLE (-5625 2050);
FORCEPROP 1 LAST PATH I16
J 2
(-5298 2175);
DISPLAY 0.872340 (-5298 2175);
PAINT GREEN (-5298 2175);
DISPLAY INVISIBLE (-5298 2175);
FORCEADD TAP..1
R 2
(-5300 2225);
FORCEPROP 3 LASTPIN (-5250 2225) SIG_NAME UPI_CPU1_CPU0_P1P1_DN<6>
J 0
(-5240 2235);
DISPLAY 0.659574 (-5240 2235);
PAINT MONO (-5240 2235);
DISPLAY INVISIBLE (-5240 2235);
FORCEPROP 1 LASTPIN (-5250 2225) BN 6
J 2
(-5238 2233);
DISPLAY 0.617021 (-5238 2233);
PAINT PINK (-5238 2233);
FORCEPROP 2 LAST CDS_LIB mstr_standard
J 0
(-5300 2225);
PAINT MONO (-5300 2225);
DISPLAY INVISIBLE (-5300 2225);
FORCEPROP 1 LAST BODY_TYPE PLUMBING
J 2
(-5300 2275);
DISPLAY 1.446809 (-5300 2275);
PAINT GREEN (-5300 2275);
DISPLAY INVISIBLE (-5300 2275);
FORCEPROP 1 LAST HDL_TAP TRUE
J 2
(-5625 2100);
DISPLAY 1.446809 (-5625 2100);
PAINT GREEN (-5625 2100);
DISPLAY INVISIBLE (-5625 2100);
FORCEPROP 1 LAST PATH I17
J 2
(-5298 2225);
DISPLAY 0.872340 (-5298 2225);
PAINT GREEN (-5298 2225);
DISPLAY INVISIBLE (-5298 2225);
FORCEADD TAP..1
R 2
(-5300 2275);
FORCEPROP 3 LASTPIN (-5250 2275) SIG_NAME UPI_CPU1_CPU0_P1P1_DN<5>
J 0
(-5240 2285);
DISPLAY 0.659574 (-5240 2285);
PAINT MONO (-5240 2285);
DISPLAY INVISIBLE (-5240 2285);
FORCEPROP 1 LASTPIN (-5250 2275) BN 5
J 2
(-5238 2283);
DISPLAY 0.617021 (-5238 2283);
PAINT PINK (-5238 2283);
FORCEPROP 2 LAST CDS_LIB mstr_standard
J 0
(-5300 2275);
PAINT MONO (-5300 2275);
DISPLAY INVISIBLE (-5300 2275);
FORCEPROP 1 LAST BODY_TYPE PLUMBING
J 2
(-5300 2325);
DISPLAY 1.446809 (-5300 2325);
PAINT GREEN (-5300 2325);
DISPLAY INVISIBLE (-5300 2325);
FORCEPROP 1 LAST HDL_TAP TRUE
J 2
(-5625 2150);
DISPLAY 1.446809 (-5625 2150);
PAINT GREEN (-5625 2150);
DISPLAY INVISIBLE (-5625 2150);
FORCEPROP 1 LAST PATH I18
J 2
(-5298 2275);
DISPLAY 0.872340 (-5298 2275);
PAINT GREEN (-5298 2275);
DISPLAY INVISIBLE (-5298 2275);
FORCEADD TAP..1
R 2
(-5300 2325);
FORCEPROP 3 LASTPIN (-5250 2325) SIG_NAME UPI_CPU1_CPU0_P1P1_DN<4>
J 0
(-5240 2335);
DISPLAY 0.659574 (-5240 2335);
PAINT MONO (-5240 2335);
DISPLAY INVISIBLE (-5240 2335);
FORCEPROP 1 LASTPIN (-5250 2325) BN 4
J 2
(-5238 2333);
DISPLAY 0.617021 (-5238 2333);
PAINT PINK (-5238 2333);
FORCEPROP 2 LAST CDS_LIB mstr_standard
J 0
(-5300 2325);
PAINT MONO (-5300 2325);
DISPLAY INVISIBLE (-5300 2325);
FORCEPROP 1 LAST BODY_TYPE PLUMBING
J 2
(-5300 2375);
DISPLAY 1.446809 (-5300 2375);
PAINT GREEN (-5300 2375);
DISPLAY INVISIBLE (-5300 2375);
FORCEPROP 1 LAST HDL_TAP TRUE
J 2
(-5625 2200);
DISPLAY 1.446809 (-5625 2200);
PAINT GREEN (-5625 2200);
DISPLAY INVISIBLE (-5625 2200);
FORCEPROP 1 LAST PATH I19
J 2
(-5298 2325);
DISPLAY 0.872340 (-5298 2325);
PAINT GREEN (-5298 2325);
DISPLAY INVISIBLE (-5298 2325);
FORCEADD OFFPAGE..1
(-6500 3625);
FORCEPROP 2 LAST $XR0 68 
J 0
(-6751 3625);
DISPLAY 0.638298 (-6751 3625);
PAINT MONO (-6751 3625);
FORCEPROP 2 LAST CDS_LIB mstr_standard
J 0
(-6500 3625);
PAINT MONO (-6500 3625);
DISPLAY INVISIBLE (-6500 3625);
FORCEPROP 1 LAST OFFPAGE TRUE
J 0
(-6175 3500);
DISPLAY 1.170213 (-6175 3500);
PAINT GREEN (-6175 3500);
DISPLAY INVISIBLE (-6175 3500);
FORCEPROP 1 LAST COMMENT_BODY TRUE
J 0
(-6375 3525);
DISPLAY 1.170213 (-6375 3525);
PAINT GREEN (-6375 3525);
DISPLAY INVISIBLE (-6375 3525);
FORCEPROP 2 LAST PATH I2
J 0
(-6450 3700);
DISPLAY 1.021277 (-6450 3700);
PAINT ORANGE (-6450 3700);
DISPLAY INVISIBLE (-6450 3700);
FORCEADD TAP..1
R 2
(-5300 2375);
FORCEPROP 3 LASTPIN (-5250 2375) SIG_NAME UPI_CPU1_CPU0_P1P1_DN<3>
J 0
(-5240 2385);
DISPLAY 0.659574 (-5240 2385);
PAINT MONO (-5240 2385);
DISPLAY INVISIBLE (-5240 2385);
FORCEPROP 1 LASTPIN (-5250 2375) BN 3
J 2
(-5238 2383);
DISPLAY 0.617021 (-5238 2383);
PAINT PINK (-5238 2383);
FORCEPROP 2 LAST CDS_LIB mstr_standard
J 0
(-5300 2375);
PAINT MONO (-5300 2375);
DISPLAY INVISIBLE (-5300 2375);
FORCEPROP 1 LAST BODY_TYPE PLUMBING
J 2
(-5300 2425);
DISPLAY 1.446809 (-5300 2425);
PAINT GREEN (-5300 2425);
DISPLAY INVISIBLE (-5300 2425);
FORCEPROP 1 LAST HDL_TAP TRUE
J 2
(-5625 2250);
DISPLAY 1.446809 (-5625 2250);
PAINT GREEN (-5625 2250);
DISPLAY INVISIBLE (-5625 2250);
FORCEPROP 1 LAST PATH I20
J 2
(-5298 2375);
DISPLAY 0.872340 (-5298 2375);
PAINT GREEN (-5298 2375);
DISPLAY INVISIBLE (-5298 2375);
FORCEADD TAP..1
R 2
(-5300 2425);
FORCEPROP 3 LASTPIN (-5250 2425) SIG_NAME UPI_CPU1_CPU0_P1P1_DN<2>
J 0
(-5240 2435);
DISPLAY 0.659574 (-5240 2435);
PAINT MONO (-5240 2435);
DISPLAY INVISIBLE (-5240 2435);
FORCEPROP 1 LASTPIN (-5250 2425) BN 2
J 2
(-5238 2433);
DISPLAY 0.617021 (-5238 2433);
PAINT PINK (-5238 2433);
FORCEPROP 2 LAST CDS_LIB mstr_standard
J 0
(-5300 2425);
PAINT MONO (-5300 2425);
DISPLAY INVISIBLE (-5300 2425);
FORCEPROP 1 LAST BODY_TYPE PLUMBING
J 2
(-5300 2475);
DISPLAY 1.446809 (-5300 2475);
PAINT GREEN (-5300 2475);
DISPLAY INVISIBLE (-5300 2475);
FORCEPROP 1 LAST HDL_TAP TRUE
J 2
(-5625 2300);
DISPLAY 1.446809 (-5625 2300);
PAINT GREEN (-5625 2300);
DISPLAY INVISIBLE (-5625 2300);
FORCEPROP 1 LAST PATH I21
J 2
(-5298 2425);
DISPLAY 0.872340 (-5298 2425);
PAINT GREEN (-5298 2425);
DISPLAY INVISIBLE (-5298 2425);
FORCEADD TAP..1
R 2
(-5300 2475);
FORCEPROP 3 LASTPIN (-5250 2475) SIG_NAME UPI_CPU1_CPU0_P1P1_DN<1>
J 0
(-5240 2485);
DISPLAY 0.659574 (-5240 2485);
PAINT MONO (-5240 2485);
DISPLAY INVISIBLE (-5240 2485);
FORCEPROP 1 LASTPIN (-5250 2475) BN 1
J 2
(-5238 2483);
DISPLAY 0.617021 (-5238 2483);
PAINT PINK (-5238 2483);
FORCEPROP 2 LAST CDS_LIB mstr_standard
J 0
(-5300 2475);
PAINT MONO (-5300 2475);
DISPLAY INVISIBLE (-5300 2475);
FORCEPROP 1 LAST BODY_TYPE PLUMBING
J 2
(-5300 2525);
DISPLAY 1.446809 (-5300 2525);
PAINT GREEN (-5300 2525);
DISPLAY INVISIBLE (-5300 2525);
FORCEPROP 1 LAST HDL_TAP TRUE
J 2
(-5625 2350);
DISPLAY 1.446809 (-5625 2350);
PAINT GREEN (-5625 2350);
DISPLAY INVISIBLE (-5625 2350);
FORCEPROP 1 LAST PATH I22
J 2
(-5298 2475);
DISPLAY 0.872340 (-5298 2475);
PAINT GREEN (-5298 2475);
DISPLAY INVISIBLE (-5298 2475);
FORCEADD TAP..1
R 2
(-5300 2525);
FORCEPROP 3 LASTPIN (-5250 2525) SIG_NAME UPI_CPU1_CPU0_P1P1_DN<0>
J 0
(-5240 2535);
DISPLAY 0.659574 (-5240 2535);
PAINT MONO (-5240 2535);
DISPLAY INVISIBLE (-5240 2535);
FORCEPROP 1 LASTPIN (-5250 2525) BN 0
J 2
(-5238 2533);
DISPLAY 0.617021 (-5238 2533);
PAINT PINK (-5238 2533);
FORCEPROP 2 LAST CDS_LIB mstr_standard
J 0
(-5300 2525);
PAINT MONO (-5300 2525);
DISPLAY INVISIBLE (-5300 2525);
FORCEPROP 1 LAST BODY_TYPE PLUMBING
J 2
(-5300 2575);
DISPLAY 1.446809 (-5300 2575);
PAINT GREEN (-5300 2575);
DISPLAY INVISIBLE (-5300 2575);
FORCEPROP 1 LAST HDL_TAP TRUE
J 2
(-5625 2400);
DISPLAY 1.446809 (-5625 2400);
PAINT GREEN (-5625 2400);
DISPLAY INVISIBLE (-5625 2400);
FORCEPROP 1 LAST PATH I23
J 2
(-5298 2525);
DISPLAY 0.872340 (-5298 2525);
PAINT GREEN (-5298 2525);
DISPLAY INVISIBLE (-5298 2525);
FORCEADD TAP..1
R 2
(-5300 2625);
FORCEPROP 3 LASTPIN (-5250 2625) SIG_NAME UPI_CPU1_CPU0_P1P1_DP<19>
J 0
(-5240 2635);
DISPLAY 0.659574 (-5240 2635);
PAINT MONO (-5240 2635);
DISPLAY INVISIBLE (-5240 2635);
FORCEPROP 1 LASTPIN (-5250 2625) BN 19
J 2
(-5238 2633);
DISPLAY 0.617021 (-5238 2633);
PAINT PINK (-5238 2633);
FORCEPROP 2 LAST CDS_LIB mstr_standard
J 0
(-5300 2625);
PAINT MONO (-5300 2625);
DISPLAY INVISIBLE (-5300 2625);
FORCEPROP 1 LAST BODY_TYPE PLUMBING
J 2
(-5300 2675);
DISPLAY 1.446809 (-5300 2675);
PAINT GREEN (-5300 2675);
DISPLAY INVISIBLE (-5300 2675);
FORCEPROP 1 LAST HDL_TAP TRUE
J 2
(-5625 2500);
DISPLAY 1.446809 (-5625 2500);
PAINT GREEN (-5625 2500);
DISPLAY INVISIBLE (-5625 2500);
FORCEPROP 1 LAST PATH I24
J 2
(-5298 2625);
DISPLAY 0.872340 (-5298 2625);
PAINT GREEN (-5298 2625);
DISPLAY INVISIBLE (-5298 2625);
FORCEADD TAP..1
R 2
(-5300 2775);
FORCEPROP 3 LASTPIN (-5250 2775) SIG_NAME UPI_CPU1_CPU0_P1P1_DP<16>
J 0
(-5240 2785);
DISPLAY 0.659574 (-5240 2785);
PAINT MONO (-5240 2785);
DISPLAY INVISIBLE (-5240 2785);
FORCEPROP 1 LASTPIN (-5250 2775) BN 16
J 2
(-5238 2783);
DISPLAY 0.617021 (-5238 2783);
PAINT PINK (-5238 2783);
FORCEPROP 2 LAST CDS_LIB mstr_standard
J 0
(-5300 2775);
PAINT MONO (-5300 2775);
DISPLAY INVISIBLE (-5300 2775);
FORCEPROP 1 LAST BODY_TYPE PLUMBING
J 2
(-5300 2825);
DISPLAY 1.446809 (-5300 2825);
PAINT GREEN (-5300 2825);
DISPLAY INVISIBLE (-5300 2825);
FORCEPROP 1 LAST HDL_TAP TRUE
J 2
(-5625 2650);
DISPLAY 1.446809 (-5625 2650);
PAINT GREEN (-5625 2650);
DISPLAY INVISIBLE (-5625 2650);
FORCEPROP 1 LAST PATH I25
J 2
(-5298 2775);
DISPLAY 0.872340 (-5298 2775);
PAINT GREEN (-5298 2775);
DISPLAY INVISIBLE (-5298 2775);
FORCEADD TAP..1
R 2
(-5300 2725);
FORCEPROP 3 LASTPIN (-5250 2725) SIG_NAME UPI_CPU1_CPU0_P1P1_DP<17>
J 0
(-5240 2735);
DISPLAY 0.659574 (-5240 2735);
PAINT MONO (-5240 2735);
DISPLAY INVISIBLE (-5240 2735);
FORCEPROP 1 LASTPIN (-5250 2725) BN 17
J 2
(-5238 2733);
DISPLAY 0.617021 (-5238 2733);
PAINT PINK (-5238 2733);
FORCEPROP 2 LAST CDS_LIB mstr_standard
J 0
(-5300 2725);
PAINT MONO (-5300 2725);
DISPLAY INVISIBLE (-5300 2725);
FORCEPROP 1 LAST BODY_TYPE PLUMBING
J 2
(-5300 2775);
DISPLAY 1.446809 (-5300 2775);
PAINT GREEN (-5300 2775);
DISPLAY INVISIBLE (-5300 2775);
FORCEPROP 1 LAST HDL_TAP TRUE
J 2
(-5625 2600);
DISPLAY 1.446809 (-5625 2600);
PAINT GREEN (-5625 2600);
DISPLAY INVISIBLE (-5625 2600);
FORCEPROP 1 LAST PATH I26
J 2
(-5298 2725);
DISPLAY 0.872340 (-5298 2725);
PAINT GREEN (-5298 2725);
DISPLAY INVISIBLE (-5298 2725);
FORCEADD TAP..1
R 2
(-5300 2675);
FORCEPROP 3 LASTPIN (-5250 2675) SIG_NAME UPI_CPU1_CPU0_P1P1_DP<18>
J 0
(-5240 2685);
DISPLAY 0.659574 (-5240 2685);
PAINT MONO (-5240 2685);
DISPLAY INVISIBLE (-5240 2685);
FORCEPROP 1 LASTPIN (-5250 2675) BN 18
J 2
(-5238 2683);
DISPLAY 0.617021 (-5238 2683);
PAINT PINK (-5238 2683);
FORCEPROP 2 LAST CDS_LIB mstr_standard
J 0
(-5300 2675);
PAINT MONO (-5300 2675);
DISPLAY INVISIBLE (-5300 2675);
FORCEPROP 1 LAST BODY_TYPE PLUMBING
J 2
(-5300 2725);
DISPLAY 1.446809 (-5300 2725);
PAINT GREEN (-5300 2725);
DISPLAY INVISIBLE (-5300 2725);
FORCEPROP 1 LAST HDL_TAP TRUE
J 2
(-5625 2550);
DISPLAY 1.446809 (-5625 2550);
PAINT GREEN (-5625 2550);
DISPLAY INVISIBLE (-5625 2550);
FORCEPROP 1 LAST PATH I27
J 2
(-5298 2675);
DISPLAY 0.872340 (-5298 2675);
PAINT GREEN (-5298 2675);
DISPLAY INVISIBLE (-5298 2675);
FORCEADD TAP..1
R 2
(-5300 2825);
FORCEPROP 3 LASTPIN (-5250 2825) SIG_NAME UPI_CPU1_CPU0_P1P1_DP<15>
J 0
(-5240 2835);
DISPLAY 0.659574 (-5240 2835);
PAINT MONO (-5240 2835);
DISPLAY INVISIBLE (-5240 2835);
FORCEPROP 1 LASTPIN (-5250 2825) BN 15
J 2
(-5238 2833);
DISPLAY 0.617021 (-5238 2833);
PAINT PINK (-5238 2833);
FORCEPROP 2 LAST CDS_LIB mstr_standard
J 0
(-5300 2825);
PAINT MONO (-5300 2825);
DISPLAY INVISIBLE (-5300 2825);
FORCEPROP 1 LAST BODY_TYPE PLUMBING
J 2
(-5300 2875);
DISPLAY 1.446809 (-5300 2875);
PAINT GREEN (-5300 2875);
DISPLAY INVISIBLE (-5300 2875);
FORCEPROP 1 LAST HDL_TAP TRUE
J 2
(-5625 2700);
DISPLAY 1.446809 (-5625 2700);
PAINT GREEN (-5625 2700);
DISPLAY INVISIBLE (-5625 2700);
FORCEPROP 1 LAST PATH I28
J 2
(-5298 2825);
DISPLAY 0.872340 (-5298 2825);
PAINT GREEN (-5298 2825);
DISPLAY INVISIBLE (-5298 2825);
FORCEADD TAP..1
R 2
(-5300 2875);
FORCEPROP 3 LASTPIN (-5250 2875) SIG_NAME UPI_CPU1_CPU0_P1P1_DP<14>
J 0
(-5240 2885);
DISPLAY 0.659574 (-5240 2885);
PAINT MONO (-5240 2885);
DISPLAY INVISIBLE (-5240 2885);
FORCEPROP 1 LASTPIN (-5250 2875) BN 14
J 2
(-5238 2883);
DISPLAY 0.617021 (-5238 2883);
PAINT PINK (-5238 2883);
FORCEPROP 2 LAST CDS_LIB mstr_standard
J 0
(-5300 2875);
PAINT MONO (-5300 2875);
DISPLAY INVISIBLE (-5300 2875);
FORCEPROP 1 LAST BODY_TYPE PLUMBING
J 2
(-5300 2925);
DISPLAY 1.446809 (-5300 2925);
PAINT GREEN (-5300 2925);
DISPLAY INVISIBLE (-5300 2925);
FORCEPROP 1 LAST HDL_TAP TRUE
J 2
(-5625 2750);
DISPLAY 1.446809 (-5625 2750);
PAINT GREEN (-5625 2750);
DISPLAY INVISIBLE (-5625 2750);
FORCEPROP 1 LAST PATH I29
J 2
(-5298 2875);
DISPLAY 0.872340 (-5298 2875);
PAINT GREEN (-5298 2875);
DISPLAY INVISIBLE (-5298 2875);
FORCEADD TAP..1
R 2
(-5300 1625);
FORCEPROP 3 LASTPIN (-5250 1625) SIG_NAME UPI_CPU1_CPU0_P1P1_DN<18>
J 0
(-5240 1635);
DISPLAY 0.659574 (-5240 1635);
PAINT MONO (-5240 1635);
DISPLAY INVISIBLE (-5240 1635);
FORCEPROP 1 LASTPIN (-5250 1625) BN 18
J 2
(-5238 1633);
DISPLAY 0.617021 (-5238 1633);
PAINT PINK (-5238 1633);
FORCEPROP 2 LAST CDS_LIB mstr_standard
J 0
(-5300 1625);
PAINT MONO (-5300 1625);
DISPLAY INVISIBLE (-5300 1625);
FORCEPROP 1 LAST BODY_TYPE PLUMBING
J 2
(-5300 1675);
DISPLAY 1.446809 (-5300 1675);
PAINT GREEN (-5300 1675);
DISPLAY INVISIBLE (-5300 1675);
FORCEPROP 1 LAST HDL_TAP TRUE
J 2
(-5625 1500);
DISPLAY 1.446809 (-5625 1500);
PAINT GREEN (-5625 1500);
DISPLAY INVISIBLE (-5625 1500);
FORCEPROP 1 LAST PATH I3
J 2
(-5298 1625);
DISPLAY 0.872340 (-5298 1625);
PAINT GREEN (-5298 1625);
DISPLAY INVISIBLE (-5298 1625);
FORCEADD TAP..1
R 2
(-5300 2925);
FORCEPROP 3 LASTPIN (-5250 2925) SIG_NAME UPI_CPU1_CPU0_P1P1_DP<13>
J 0
(-5240 2935);
DISPLAY 0.659574 (-5240 2935);
PAINT MONO (-5240 2935);
DISPLAY INVISIBLE (-5240 2935);
FORCEPROP 1 LASTPIN (-5250 2925) BN 13
J 2
(-5238 2933);
DISPLAY 0.617021 (-5238 2933);
PAINT PINK (-5238 2933);
FORCEPROP 2 LAST CDS_LIB mstr_standard
J 0
(-5300 2925);
PAINT MONO (-5300 2925);
DISPLAY INVISIBLE (-5300 2925);
FORCEPROP 1 LAST BODY_TYPE PLUMBING
J 2
(-5300 2975);
DISPLAY 1.446809 (-5300 2975);
PAINT GREEN (-5300 2975);
DISPLAY INVISIBLE (-5300 2975);
FORCEPROP 1 LAST HDL_TAP TRUE
J 2
(-5625 2800);
DISPLAY 1.446809 (-5625 2800);
PAINT GREEN (-5625 2800);
DISPLAY INVISIBLE (-5625 2800);
FORCEPROP 1 LAST PATH I30
J 2
(-5298 2925);
DISPLAY 0.872340 (-5298 2925);
PAINT GREEN (-5298 2925);
DISPLAY INVISIBLE (-5298 2925);
FORCEADD TAP..1
R 2
(-5300 2975);
FORCEPROP 3 LASTPIN (-5250 2975) SIG_NAME UPI_CPU1_CPU0_P1P1_DP<12>
J 0
(-5240 2985);
DISPLAY 0.659574 (-5240 2985);
PAINT MONO (-5240 2985);
DISPLAY INVISIBLE (-5240 2985);
FORCEPROP 1 LASTPIN (-5250 2975) BN 12
J 2
(-5238 2983);
DISPLAY 0.617021 (-5238 2983);
PAINT PINK (-5238 2983);
FORCEPROP 2 LAST CDS_LIB mstr_standard
J 0
(-5300 2975);
PAINT MONO (-5300 2975);
DISPLAY INVISIBLE (-5300 2975);
FORCEPROP 1 LAST BODY_TYPE PLUMBING
J 2
(-5300 3025);
DISPLAY 1.446809 (-5300 3025);
PAINT GREEN (-5300 3025);
DISPLAY INVISIBLE (-5300 3025);
FORCEPROP 1 LAST HDL_TAP TRUE
J 2
(-5625 2850);
DISPLAY 1.446809 (-5625 2850);
PAINT GREEN (-5625 2850);
DISPLAY INVISIBLE (-5625 2850);
FORCEPROP 1 LAST PATH I31
J 2
(-5298 2975);
DISPLAY 0.872340 (-5298 2975);
PAINT GREEN (-5298 2975);
DISPLAY INVISIBLE (-5298 2975);
FORCEADD TAP..1
R 2
(-5300 3075);
FORCEPROP 3 LASTPIN (-5250 3075) SIG_NAME UPI_CPU1_CPU0_P1P1_DP<10>
J 0
(-5240 3085);
DISPLAY 0.659574 (-5240 3085);
PAINT MONO (-5240 3085);
DISPLAY INVISIBLE (-5240 3085);
FORCEPROP 1 LASTPIN (-5250 3075) BN 10
J 2
(-5238 3083);
DISPLAY 0.617021 (-5238 3083);
PAINT PINK (-5238 3083);
FORCEPROP 2 LAST CDS_LIB mstr_standard
J 0
(-5300 3075);
PAINT MONO (-5300 3075);
DISPLAY INVISIBLE (-5300 3075);
FORCEPROP 1 LAST BODY_TYPE PLUMBING
J 2
(-5300 3125);
DISPLAY 1.446809 (-5300 3125);
PAINT GREEN (-5300 3125);
DISPLAY INVISIBLE (-5300 3125);
FORCEPROP 1 LAST HDL_TAP TRUE
J 2
(-5625 2950);
DISPLAY 1.446809 (-5625 2950);
PAINT GREEN (-5625 2950);
DISPLAY INVISIBLE (-5625 2950);
FORCEPROP 1 LAST PATH I32
J 2
(-5298 3075);
DISPLAY 0.872340 (-5298 3075);
PAINT GREEN (-5298 3075);
DISPLAY INVISIBLE (-5298 3075);
FORCEADD TAP..1
R 2
(-5300 3025);
FORCEPROP 3 LASTPIN (-5250 3025) SIG_NAME UPI_CPU1_CPU0_P1P1_DP<11>
J 0
(-5240 3035);
DISPLAY 0.659574 (-5240 3035);
PAINT MONO (-5240 3035);
DISPLAY INVISIBLE (-5240 3035);
FORCEPROP 1 LASTPIN (-5250 3025) BN 11
J 2
(-5238 3033);
DISPLAY 0.617021 (-5238 3033);
PAINT PINK (-5238 3033);
FORCEPROP 2 LAST CDS_LIB mstr_standard
J 0
(-5300 3025);
PAINT MONO (-5300 3025);
DISPLAY INVISIBLE (-5300 3025);
FORCEPROP 1 LAST BODY_TYPE PLUMBING
J 2
(-5300 3075);
DISPLAY 1.446809 (-5300 3075);
PAINT GREEN (-5300 3075);
DISPLAY INVISIBLE (-5300 3075);
FORCEPROP 1 LAST HDL_TAP TRUE
J 2
(-5625 2900);
DISPLAY 1.446809 (-5625 2900);
PAINT GREEN (-5625 2900);
DISPLAY INVISIBLE (-5625 2900);
FORCEPROP 1 LAST PATH I33
J 2
(-5298 3025);
DISPLAY 0.872340 (-5298 3025);
PAINT GREEN (-5298 3025);
DISPLAY INVISIBLE (-5298 3025);
FORCEADD TAP..1
R 2
(-5300 3125);
FORCEPROP 3 LASTPIN (-5250 3125) SIG_NAME UPI_CPU1_CPU0_P1P1_DP<9>
J 0
(-5240 3135);
DISPLAY 0.659574 (-5240 3135);
PAINT MONO (-5240 3135);
DISPLAY INVISIBLE (-5240 3135);
FORCEPROP 1 LASTPIN (-5250 3125) BN 9
J 2
(-5238 3133);
DISPLAY 0.617021 (-5238 3133);
PAINT PINK (-5238 3133);
FORCEPROP 2 LAST CDS_LIB mstr_standard
J 0
(-5300 3125);
PAINT MONO (-5300 3125);
DISPLAY INVISIBLE (-5300 3125);
FORCEPROP 1 LAST BODY_TYPE PLUMBING
J 2
(-5300 3175);
DISPLAY 1.446809 (-5300 3175);
PAINT GREEN (-5300 3175);
DISPLAY INVISIBLE (-5300 3175);
FORCEPROP 1 LAST HDL_TAP TRUE
J 2
(-5625 3000);
DISPLAY 1.446809 (-5625 3000);
PAINT GREEN (-5625 3000);
DISPLAY INVISIBLE (-5625 3000);
FORCEPROP 1 LAST PATH I34
J 2
(-5298 3125);
DISPLAY 0.872340 (-5298 3125);
PAINT GREEN (-5298 3125);
DISPLAY INVISIBLE (-5298 3125);
FORCEADD TAP..1
R 2
(-5300 3175);
FORCEPROP 3 LASTPIN (-5250 3175) SIG_NAME UPI_CPU1_CPU0_P1P1_DP<8>
J 0
(-5240 3185);
DISPLAY 0.659574 (-5240 3185);
PAINT MONO (-5240 3185);
DISPLAY INVISIBLE (-5240 3185);
FORCEPROP 1 LASTPIN (-5250 3175) BN 8
J 2
(-5238 3183);
DISPLAY 0.617021 (-5238 3183);
PAINT PINK (-5238 3183);
FORCEPROP 2 LAST CDS_LIB mstr_standard
J 0
(-5300 3175);
PAINT MONO (-5300 3175);
DISPLAY INVISIBLE (-5300 3175);
FORCEPROP 1 LAST BODY_TYPE PLUMBING
J 2
(-5300 3225);
DISPLAY 1.446809 (-5300 3225);
PAINT GREEN (-5300 3225);
DISPLAY INVISIBLE (-5300 3225);
FORCEPROP 1 LAST HDL_TAP TRUE
J 2
(-5625 3050);
DISPLAY 1.446809 (-5625 3050);
PAINT GREEN (-5625 3050);
DISPLAY INVISIBLE (-5625 3050);
FORCEPROP 1 LAST PATH I35
J 2
(-5298 3175);
DISPLAY 0.872340 (-5298 3175);
PAINT GREEN (-5298 3175);
DISPLAY INVISIBLE (-5298 3175);
FORCEADD TAP..1
R 2
(-5300 3225);
FORCEPROP 3 LASTPIN (-5250 3225) SIG_NAME UPI_CPU1_CPU0_P1P1_DP<7>
J 0
(-5240 3235);
DISPLAY 0.659574 (-5240 3235);
PAINT MONO (-5240 3235);
DISPLAY INVISIBLE (-5240 3235);
FORCEPROP 1 LASTPIN (-5250 3225) BN 7
J 2
(-5238 3233);
DISPLAY 0.617021 (-5238 3233);
PAINT PINK (-5238 3233);
FORCEPROP 2 LAST CDS_LIB mstr_standard
J 0
(-5300 3225);
PAINT MONO (-5300 3225);
DISPLAY INVISIBLE (-5300 3225);
FORCEPROP 1 LAST BODY_TYPE PLUMBING
J 2
(-5300 3275);
DISPLAY 1.446809 (-5300 3275);
PAINT GREEN (-5300 3275);
DISPLAY INVISIBLE (-5300 3275);
FORCEPROP 1 LAST HDL_TAP TRUE
J 2
(-5625 3100);
DISPLAY 1.446809 (-5625 3100);
PAINT GREEN (-5625 3100);
DISPLAY INVISIBLE (-5625 3100);
FORCEPROP 1 LAST PATH I36
J 2
(-5298 3225);
DISPLAY 0.872340 (-5298 3225);
PAINT GREEN (-5298 3225);
DISPLAY INVISIBLE (-5298 3225);
FORCEADD TAP..1
R 2
(-5300 3325);
FORCEPROP 3 LASTPIN (-5250 3325) SIG_NAME UPI_CPU1_CPU0_P1P1_DP<5>
J 0
(-5240 3335);
DISPLAY 0.659574 (-5240 3335);
PAINT MONO (-5240 3335);
DISPLAY INVISIBLE (-5240 3335);
FORCEPROP 1 LASTPIN (-5250 3325) BN 5
J 2
(-5238 3333);
DISPLAY 0.617021 (-5238 3333);
PAINT PINK (-5238 3333);
FORCEPROP 2 LAST CDS_LIB mstr_standard
J 0
(-5300 3325);
PAINT MONO (-5300 3325);
DISPLAY INVISIBLE (-5300 3325);
FORCEPROP 1 LAST BODY_TYPE PLUMBING
J 2
(-5300 3375);
DISPLAY 1.446809 (-5300 3375);
PAINT GREEN (-5300 3375);
DISPLAY INVISIBLE (-5300 3375);
FORCEPROP 1 LAST HDL_TAP TRUE
J 2
(-5625 3200);
DISPLAY 1.446809 (-5625 3200);
PAINT GREEN (-5625 3200);
DISPLAY INVISIBLE (-5625 3200);
FORCEPROP 1 LAST PATH I37
J 2
(-5298 3325);
DISPLAY 0.872340 (-5298 3325);
PAINT GREEN (-5298 3325);
DISPLAY INVISIBLE (-5298 3325);
FORCEADD TAP..1
R 2
(-5300 3275);
FORCEPROP 3 LASTPIN (-5250 3275) SIG_NAME UPI_CPU1_CPU0_P1P1_DP<6>
J 0
(-5240 3285);
DISPLAY 0.659574 (-5240 3285);
PAINT MONO (-5240 3285);
DISPLAY INVISIBLE (-5240 3285);
FORCEPROP 1 LASTPIN (-5250 3275) BN 6
J 2
(-5238 3283);
DISPLAY 0.617021 (-5238 3283);
PAINT PINK (-5238 3283);
FORCEPROP 2 LAST CDS_LIB mstr_standard
J 0
(-5300 3275);
PAINT MONO (-5300 3275);
DISPLAY INVISIBLE (-5300 3275);
FORCEPROP 1 LAST BODY_TYPE PLUMBING
J 2
(-5300 3325);
DISPLAY 1.446809 (-5300 3325);
PAINT GREEN (-5300 3325);
DISPLAY INVISIBLE (-5300 3325);
FORCEPROP 1 LAST HDL_TAP TRUE
J 2
(-5625 3150);
DISPLAY 1.446809 (-5625 3150);
PAINT GREEN (-5625 3150);
DISPLAY INVISIBLE (-5625 3150);
FORCEPROP 1 LAST PATH I38
J 2
(-5298 3275);
DISPLAY 0.872340 (-5298 3275);
PAINT GREEN (-5298 3275);
DISPLAY INVISIBLE (-5298 3275);
FORCEADD TAP..1
R 2
(-5300 3375);
FORCEPROP 3 LASTPIN (-5250 3375) SIG_NAME UPI_CPU1_CPU0_P1P1_DP<4>
J 0
(-5240 3385);
DISPLAY 0.659574 (-5240 3385);
PAINT MONO (-5240 3385);
DISPLAY INVISIBLE (-5240 3385);
FORCEPROP 1 LASTPIN (-5250 3375) BN 4
J 2
(-5238 3383);
DISPLAY 0.617021 (-5238 3383);
PAINT PINK (-5238 3383);
FORCEPROP 2 LAST CDS_LIB mstr_standard
J 0
(-5300 3375);
PAINT MONO (-5300 3375);
DISPLAY INVISIBLE (-5300 3375);
FORCEPROP 1 LAST BODY_TYPE PLUMBING
J 2
(-5300 3425);
DISPLAY 1.446809 (-5300 3425);
PAINT GREEN (-5300 3425);
DISPLAY INVISIBLE (-5300 3425);
FORCEPROP 1 LAST HDL_TAP TRUE
J 2
(-5625 3250);
DISPLAY 1.446809 (-5625 3250);
PAINT GREEN (-5625 3250);
DISPLAY INVISIBLE (-5625 3250);
FORCEPROP 1 LAST PATH I39
J 2
(-5298 3375);
DISPLAY 0.872340 (-5298 3375);
PAINT GREEN (-5298 3375);
DISPLAY INVISIBLE (-5298 3375);
FORCEADD TAP..1
R 2
(-5300 1575);
FORCEPROP 3 LASTPIN (-5250 1575) SIG_NAME UPI_CPU1_CPU0_P1P1_DN<19>
J 0
(-5240 1585);
DISPLAY 0.659574 (-5240 1585);
PAINT MONO (-5240 1585);
DISPLAY INVISIBLE (-5240 1585);
FORCEPROP 1 LASTPIN (-5250 1575) BN 19
J 2
(-5238 1583);
DISPLAY 0.617021 (-5238 1583);
PAINT PINK (-5238 1583);
FORCEPROP 2 LAST CDS_LIB mstr_standard
J 0
(-5300 1575);
PAINT MONO (-5300 1575);
DISPLAY INVISIBLE (-5300 1575);
FORCEPROP 1 LAST BODY_TYPE PLUMBING
J 2
(-5300 1625);
DISPLAY 1.446809 (-5300 1625);
PAINT GREEN (-5300 1625);
DISPLAY INVISIBLE (-5300 1625);
FORCEPROP 1 LAST HDL_TAP TRUE
J 2
(-5625 1450);
DISPLAY 1.446809 (-5625 1450);
PAINT GREEN (-5625 1450);
DISPLAY INVISIBLE (-5625 1450);
FORCEPROP 1 LAST PATH I4
J 2
(-5298 1575);
DISPLAY 0.872340 (-5298 1575);
PAINT GREEN (-5298 1575);
DISPLAY INVISIBLE (-5298 1575);
FORCEADD TAP..1
R 2
(-5300 3425);
FORCEPROP 3 LASTPIN (-5250 3425) SIG_NAME UPI_CPU1_CPU0_P1P1_DP<3>
J 0
(-5240 3435);
DISPLAY 0.659574 (-5240 3435);
PAINT MONO (-5240 3435);
DISPLAY INVISIBLE (-5240 3435);
FORCEPROP 1 LASTPIN (-5250 3425) BN 3
J 2
(-5238 3433);
DISPLAY 0.617021 (-5238 3433);
PAINT PINK (-5238 3433);
FORCEPROP 2 LAST CDS_LIB mstr_standard
J 0
(-5300 3425);
PAINT MONO (-5300 3425);
DISPLAY INVISIBLE (-5300 3425);
FORCEPROP 1 LAST BODY_TYPE PLUMBING
J 2
(-5300 3475);
DISPLAY 1.446809 (-5300 3475);
PAINT GREEN (-5300 3475);
DISPLAY INVISIBLE (-5300 3475);
FORCEPROP 1 LAST HDL_TAP TRUE
J 2
(-5625 3300);
DISPLAY 1.446809 (-5625 3300);
PAINT GREEN (-5625 3300);
DISPLAY INVISIBLE (-5625 3300);
FORCEPROP 1 LAST PATH I40
J 2
(-5298 3425);
DISPLAY 0.872340 (-5298 3425);
PAINT GREEN (-5298 3425);
DISPLAY INVISIBLE (-5298 3425);
FORCEADD TAP..1
R 2
(-5300 3475);
FORCEPROP 3 LASTPIN (-5250 3475) SIG_NAME UPI_CPU1_CPU0_P1P1_DP<2>
J 0
(-5240 3485);
DISPLAY 0.659574 (-5240 3485);
PAINT MONO (-5240 3485);
DISPLAY INVISIBLE (-5240 3485);
FORCEPROP 1 LASTPIN (-5250 3475) BN 2
J 2
(-5238 3483);
DISPLAY 0.617021 (-5238 3483);
PAINT PINK (-5238 3483);
FORCEPROP 2 LAST CDS_LIB mstr_standard
J 0
(-5300 3475);
PAINT MONO (-5300 3475);
DISPLAY INVISIBLE (-5300 3475);
FORCEPROP 1 LAST BODY_TYPE PLUMBING
J 2
(-5300 3525);
DISPLAY 1.446809 (-5300 3525);
PAINT GREEN (-5300 3525);
DISPLAY INVISIBLE (-5300 3525);
FORCEPROP 1 LAST HDL_TAP TRUE
J 2
(-5625 3350);
DISPLAY 1.446809 (-5625 3350);
PAINT GREEN (-5625 3350);
DISPLAY INVISIBLE (-5625 3350);
FORCEPROP 1 LAST PATH I41
J 2
(-5298 3475);
DISPLAY 0.872340 (-5298 3475);
PAINT GREEN (-5298 3475);
DISPLAY INVISIBLE (-5298 3475);
FORCEADD TAP..1
R 2
(-5300 3575);
FORCEPROP 3 LASTPIN (-5250 3575) SIG_NAME UPI_CPU1_CPU0_P1P1_DP<0>
J 0
(-5240 3585);
DISPLAY 0.659574 (-5240 3585);
PAINT MONO (-5240 3585);
DISPLAY INVISIBLE (-5240 3585);
FORCEPROP 1 LASTPIN (-5250 3575) BN 0
J 2
(-5238 3583);
DISPLAY 0.617021 (-5238 3583);
PAINT PINK (-5238 3583);
FORCEPROP 2 LAST CDS_LIB mstr_standard
J 0
(-5300 3575);
PAINT MONO (-5300 3575);
DISPLAY INVISIBLE (-5300 3575);
FORCEPROP 1 LAST BODY_TYPE PLUMBING
J 2
(-5300 3625);
DISPLAY 1.446809 (-5300 3625);
PAINT GREEN (-5300 3625);
DISPLAY INVISIBLE (-5300 3625);
FORCEPROP 1 LAST HDL_TAP TRUE
J 2
(-5625 3450);
DISPLAY 1.446809 (-5625 3450);
PAINT GREEN (-5625 3450);
DISPLAY INVISIBLE (-5625 3450);
FORCEPROP 1 LAST PATH I42
J 2
(-5298 3575);
DISPLAY 0.872340 (-5298 3575);
PAINT GREEN (-5298 3575);
DISPLAY INVISIBLE (-5298 3575);
FORCEADD TAP..1
R 2
(-5300 3525);
FORCEPROP 3 LASTPIN (-5250 3525) SIG_NAME UPI_CPU1_CPU0_P1P1_DP<1>
J 0
(-5240 3535);
DISPLAY 0.659574 (-5240 3535);
PAINT MONO (-5240 3535);
DISPLAY INVISIBLE (-5240 3535);
FORCEPROP 1 LASTPIN (-5250 3525) BN 1
J 2
(-5238 3533);
DISPLAY 0.617021 (-5238 3533);
PAINT PINK (-5238 3533);
FORCEPROP 2 LAST CDS_LIB mstr_standard
J 0
(-5300 3525);
PAINT MONO (-5300 3525);
DISPLAY INVISIBLE (-5300 3525);
FORCEPROP 1 LAST BODY_TYPE PLUMBING
J 2
(-5300 3575);
DISPLAY 1.446809 (-5300 3575);
PAINT GREEN (-5300 3575);
DISPLAY INVISIBLE (-5300 3575);
FORCEPROP 1 LAST HDL_TAP TRUE
J 2
(-5625 3400);
DISPLAY 1.446809 (-5625 3400);
PAINT GREEN (-5625 3400);
DISPLAY INVISIBLE (-5625 3400);
FORCEPROP 1 LAST PATH I43
J 2
(-5298 3525);
DISPLAY 0.872340 (-5298 3525);
PAINT GREEN (-5298 3525);
DISPLAY INVISIBLE (-5298 3525);
FORCEADD TAP..1
(-2975 1575);
FORCEPROP 3 LASTPIN (-3025 1575) SIG_NAME UPI_CPU0_CPU1_P1P1_DN<19>
J 0
(-3015 1585);
DISPLAY 0.659574 (-3015 1585);
PAINT MONO (-3015 1585);
DISPLAY INVISIBLE (-3015 1585);
FORCEPROP 1 LASTPIN (-3025 1575) BN 19
J 0
(-3037 1583);
DISPLAY 0.617021 (-3037 1583);
PAINT PINK (-3037 1583);
FORCEPROP 2 LAST CDS_LIB mstr_standard
J 0
(-2975 1575);
PAINT MONO (-2975 1575);
DISPLAY INVISIBLE (-2975 1575);
FORCEPROP 1 LAST BODY_TYPE PLUMBING
J 0
(-2975 1625);
DISPLAY 1.446809 (-2975 1625);
PAINT GREEN (-2975 1625);
DISPLAY INVISIBLE (-2975 1625);
FORCEPROP 1 LAST HDL_TAP TRUE
J 0
(-2650 1450);
DISPLAY 1.446809 (-2650 1450);
PAINT GREEN (-2650 1450);
DISPLAY INVISIBLE (-2650 1450);
FORCEPROP 1 LAST PATH I44
J 0
(-2977 1575);
DISPLAY 0.872340 (-2977 1575);
PAINT GREEN (-2977 1575);
DISPLAY INVISIBLE (-2977 1575);
FORCEADD TAP..1
(-2975 1625);
FORCEPROP 3 LASTPIN (-3025 1625) SIG_NAME UPI_CPU0_CPU1_P1P1_DN<18>
J 0
(-3015 1635);
DISPLAY 0.659574 (-3015 1635);
PAINT MONO (-3015 1635);
DISPLAY INVISIBLE (-3015 1635);
FORCEPROP 1 LASTPIN (-3025 1625) BN 18
J 0
(-3037 1633);
DISPLAY 0.617021 (-3037 1633);
PAINT PINK (-3037 1633);
FORCEPROP 2 LAST CDS_LIB mstr_standard
J 0
(-2975 1625);
PAINT MONO (-2975 1625);
DISPLAY INVISIBLE (-2975 1625);
FORCEPROP 1 LAST BODY_TYPE PLUMBING
J 0
(-2975 1675);
DISPLAY 1.446809 (-2975 1675);
PAINT GREEN (-2975 1675);
DISPLAY INVISIBLE (-2975 1675);
FORCEPROP 1 LAST HDL_TAP TRUE
J 0
(-2650 1500);
DISPLAY 1.446809 (-2650 1500);
PAINT GREEN (-2650 1500);
DISPLAY INVISIBLE (-2650 1500);
FORCEPROP 1 LAST PATH I45
J 0
(-2977 1625);
DISPLAY 0.872340 (-2977 1625);
PAINT GREEN (-2977 1625);
DISPLAY INVISIBLE (-2977 1625);
FORCEADD TAP..1
(-2975 1675);
FORCEPROP 3 LASTPIN (-3025 1675) SIG_NAME UPI_CPU0_CPU1_P1P1_DN<17>
J 0
(-3015 1685);
DISPLAY 0.659574 (-3015 1685);
PAINT MONO (-3015 1685);
DISPLAY INVISIBLE (-3015 1685);
FORCEPROP 1 LASTPIN (-3025 1675) BN 17
J 0
(-3037 1683);
DISPLAY 0.617021 (-3037 1683);
PAINT PINK (-3037 1683);
FORCEPROP 2 LAST CDS_LIB mstr_standard
J 0
(-2975 1675);
PAINT MONO (-2975 1675);
DISPLAY INVISIBLE (-2975 1675);
FORCEPROP 1 LAST BODY_TYPE PLUMBING
J 0
(-2975 1725);
DISPLAY 1.446809 (-2975 1725);
PAINT GREEN (-2975 1725);
DISPLAY INVISIBLE (-2975 1725);
FORCEPROP 1 LAST HDL_TAP TRUE
J 0
(-2650 1550);
DISPLAY 1.446809 (-2650 1550);
PAINT GREEN (-2650 1550);
DISPLAY INVISIBLE (-2650 1550);
FORCEPROP 1 LAST PATH I46
J 0
(-2977 1675);
DISPLAY 0.872340 (-2977 1675);
PAINT GREEN (-2977 1675);
DISPLAY INVISIBLE (-2977 1675);
FORCEADD TAP..1
(-2975 1725);
FORCEPROP 3 LASTPIN (-3025 1725) SIG_NAME UPI_CPU0_CPU1_P1P1_DN<16>
J 0
(-3015 1735);
DISPLAY 0.659574 (-3015 1735);
PAINT MONO (-3015 1735);
DISPLAY INVISIBLE (-3015 1735);
FORCEPROP 1 LASTPIN (-3025 1725) BN 16
J 0
(-3037 1733);
DISPLAY 0.617021 (-3037 1733);
PAINT PINK (-3037 1733);
FORCEPROP 2 LAST CDS_LIB mstr_standard
J 0
(-2975 1725);
PAINT MONO (-2975 1725);
DISPLAY INVISIBLE (-2975 1725);
FORCEPROP 1 LAST BODY_TYPE PLUMBING
J 0
(-2975 1775);
DISPLAY 1.446809 (-2975 1775);
PAINT GREEN (-2975 1775);
DISPLAY INVISIBLE (-2975 1775);
FORCEPROP 1 LAST HDL_TAP TRUE
J 0
(-2650 1600);
DISPLAY 1.446809 (-2650 1600);
PAINT GREEN (-2650 1600);
DISPLAY INVISIBLE (-2650 1600);
FORCEPROP 1 LAST PATH I47
J 0
(-2977 1725);
DISPLAY 0.872340 (-2977 1725);
PAINT GREEN (-2977 1725);
DISPLAY INVISIBLE (-2977 1725);
FORCEADD TAP..1
(-2975 1775);
FORCEPROP 3 LASTPIN (-3025 1775) SIG_NAME UPI_CPU0_CPU1_P1P1_DN<15>
J 0
(-3015 1785);
DISPLAY 0.659574 (-3015 1785);
PAINT MONO (-3015 1785);
DISPLAY INVISIBLE (-3015 1785);
FORCEPROP 1 LASTPIN (-3025 1775) BN 15
J 0
(-3037 1783);
DISPLAY 0.617021 (-3037 1783);
PAINT PINK (-3037 1783);
FORCEPROP 2 LAST CDS_LIB mstr_standard
J 0
(-2975 1775);
PAINT MONO (-2975 1775);
DISPLAY INVISIBLE (-2975 1775);
FORCEPROP 1 LAST BODY_TYPE PLUMBING
J 0
(-2975 1825);
DISPLAY 1.446809 (-2975 1825);
PAINT GREEN (-2975 1825);
DISPLAY INVISIBLE (-2975 1825);
FORCEPROP 1 LAST HDL_TAP TRUE
J 0
(-2650 1650);
DISPLAY 1.446809 (-2650 1650);
PAINT GREEN (-2650 1650);
DISPLAY INVISIBLE (-2650 1650);
FORCEPROP 1 LAST PATH I48
J 0
(-2977 1775);
DISPLAY 0.872340 (-2977 1775);
PAINT GREEN (-2977 1775);
DISPLAY INVISIBLE (-2977 1775);
FORCEADD TAP..1
(-2975 1825);
FORCEPROP 3 LASTPIN (-3025 1825) SIG_NAME UPI_CPU0_CPU1_P1P1_DN<14>
J 0
(-3015 1835);
DISPLAY 0.659574 (-3015 1835);
PAINT MONO (-3015 1835);
DISPLAY INVISIBLE (-3015 1835);
FORCEPROP 1 LASTPIN (-3025 1825) BN 14
J 0
(-3037 1833);
DISPLAY 0.617021 (-3037 1833);
PAINT PINK (-3037 1833);
FORCEPROP 2 LAST CDS_LIB mstr_standard
J 0
(-2975 1825);
PAINT MONO (-2975 1825);
DISPLAY INVISIBLE (-2975 1825);
FORCEPROP 1 LAST BODY_TYPE PLUMBING
J 0
(-2975 1875);
DISPLAY 1.446809 (-2975 1875);
PAINT GREEN (-2975 1875);
DISPLAY INVISIBLE (-2975 1875);
FORCEPROP 1 LAST HDL_TAP TRUE
J 0
(-2650 1700);
DISPLAY 1.446809 (-2650 1700);
PAINT GREEN (-2650 1700);
DISPLAY INVISIBLE (-2650 1700);
FORCEPROP 1 LAST PATH I49
J 0
(-2977 1825);
DISPLAY 0.872340 (-2977 1825);
PAINT GREEN (-2977 1825);
DISPLAY INVISIBLE (-2977 1825);
FORCEADD TAP..1
R 2
(-5300 1675);
FORCEPROP 3 LASTPIN (-5250 1675) SIG_NAME UPI_CPU1_CPU0_P1P1_DN<17>
J 0
(-5240 1685);
DISPLAY 0.659574 (-5240 1685);
PAINT MONO (-5240 1685);
DISPLAY INVISIBLE (-5240 1685);
FORCEPROP 1 LASTPIN (-5250 1675) BN 17
J 2
(-5238 1683);
DISPLAY 0.617021 (-5238 1683);
PAINT PINK (-5238 1683);
FORCEPROP 2 LAST CDS_LIB mstr_standard
J 0
(-5300 1675);
PAINT MONO (-5300 1675);
DISPLAY INVISIBLE (-5300 1675);
FORCEPROP 1 LAST BODY_TYPE PLUMBING
J 2
(-5300 1725);
DISPLAY 1.446809 (-5300 1725);
PAINT GREEN (-5300 1725);
DISPLAY INVISIBLE (-5300 1725);
FORCEPROP 1 LAST HDL_TAP TRUE
J 2
(-5625 1550);
DISPLAY 1.446809 (-5625 1550);
PAINT GREEN (-5625 1550);
DISPLAY INVISIBLE (-5625 1550);
FORCEPROP 1 LAST PATH I5
J 2
(-5298 1675);
DISPLAY 0.872340 (-5298 1675);
PAINT GREEN (-5298 1675);
DISPLAY INVISIBLE (-5298 1675);
FORCEADD TAP..1
(-2975 1875);
FORCEPROP 3 LASTPIN (-3025 1875) SIG_NAME UPI_CPU0_CPU1_P1P1_DN<13>
J 0
(-3015 1885);
DISPLAY 0.659574 (-3015 1885);
PAINT MONO (-3015 1885);
DISPLAY INVISIBLE (-3015 1885);
FORCEPROP 1 LASTPIN (-3025 1875) BN 13
J 0
(-3037 1883);
DISPLAY 0.617021 (-3037 1883);
PAINT PINK (-3037 1883);
FORCEPROP 2 LAST CDS_LIB mstr_standard
J 0
(-2975 1875);
PAINT MONO (-2975 1875);
DISPLAY INVISIBLE (-2975 1875);
FORCEPROP 1 LAST BODY_TYPE PLUMBING
J 0
(-2975 1925);
DISPLAY 1.446809 (-2975 1925);
PAINT GREEN (-2975 1925);
DISPLAY INVISIBLE (-2975 1925);
FORCEPROP 1 LAST HDL_TAP TRUE
J 0
(-2650 1750);
DISPLAY 1.446809 (-2650 1750);
PAINT GREEN (-2650 1750);
DISPLAY INVISIBLE (-2650 1750);
FORCEPROP 1 LAST PATH I50
J 0
(-2977 1875);
DISPLAY 0.872340 (-2977 1875);
PAINT GREEN (-2977 1875);
DISPLAY INVISIBLE (-2977 1875);
FORCEADD TAP..1
(-2975 1925);
FORCEPROP 3 LASTPIN (-3025 1925) SIG_NAME UPI_CPU0_CPU1_P1P1_DN<12>
J 0
(-3015 1935);
DISPLAY 0.659574 (-3015 1935);
PAINT MONO (-3015 1935);
DISPLAY INVISIBLE (-3015 1935);
FORCEPROP 1 LASTPIN (-3025 1925) BN 12
J 0
(-3037 1933);
DISPLAY 0.617021 (-3037 1933);
PAINT PINK (-3037 1933);
FORCEPROP 2 LAST CDS_LIB mstr_standard
J 0
(-2975 1925);
PAINT MONO (-2975 1925);
DISPLAY INVISIBLE (-2975 1925);
FORCEPROP 1 LAST BODY_TYPE PLUMBING
J 0
(-2975 1975);
DISPLAY 1.446809 (-2975 1975);
PAINT GREEN (-2975 1975);
DISPLAY INVISIBLE (-2975 1975);
FORCEPROP 1 LAST HDL_TAP TRUE
J 0
(-2650 1800);
DISPLAY 1.446809 (-2650 1800);
PAINT GREEN (-2650 1800);
DISPLAY INVISIBLE (-2650 1800);
FORCEPROP 1 LAST PATH I51
J 0
(-2977 1925);
DISPLAY 0.872340 (-2977 1925);
PAINT GREEN (-2977 1925);
DISPLAY INVISIBLE (-2977 1925);
FORCEADD TAP..1
(-2975 1975);
FORCEPROP 3 LASTPIN (-3025 1975) SIG_NAME UPI_CPU0_CPU1_P1P1_DN<11>
J 0
(-3015 1985);
DISPLAY 0.659574 (-3015 1985);
PAINT MONO (-3015 1985);
DISPLAY INVISIBLE (-3015 1985);
FORCEPROP 1 LASTPIN (-3025 1975) BN 11
J 0
(-3037 1983);
DISPLAY 0.617021 (-3037 1983);
PAINT PINK (-3037 1983);
FORCEPROP 2 LAST CDS_LIB mstr_standard
J 0
(-2975 1975);
PAINT MONO (-2975 1975);
DISPLAY INVISIBLE (-2975 1975);
FORCEPROP 1 LAST BODY_TYPE PLUMBING
J 0
(-2975 2025);
DISPLAY 1.446809 (-2975 2025);
PAINT GREEN (-2975 2025);
DISPLAY INVISIBLE (-2975 2025);
FORCEPROP 1 LAST HDL_TAP TRUE
J 0
(-2650 1850);
DISPLAY 1.446809 (-2650 1850);
PAINT GREEN (-2650 1850);
DISPLAY INVISIBLE (-2650 1850);
FORCEPROP 1 LAST PATH I52
J 0
(-2977 1975);
DISPLAY 0.872340 (-2977 1975);
PAINT GREEN (-2977 1975);
DISPLAY INVISIBLE (-2977 1975);
FORCEADD TAP..1
(-2975 2025);
FORCEPROP 3 LASTPIN (-3025 2025) SIG_NAME UPI_CPU0_CPU1_P1P1_DN<10>
J 0
(-3015 2035);
DISPLAY 0.659574 (-3015 2035);
PAINT MONO (-3015 2035);
DISPLAY INVISIBLE (-3015 2035);
FORCEPROP 1 LASTPIN (-3025 2025) BN 10
J 0
(-3037 2033);
DISPLAY 0.617021 (-3037 2033);
PAINT PINK (-3037 2033);
FORCEPROP 2 LAST CDS_LIB mstr_standard
J 0
(-2975 2025);
PAINT MONO (-2975 2025);
DISPLAY INVISIBLE (-2975 2025);
FORCEPROP 1 LAST BODY_TYPE PLUMBING
J 0
(-2975 2075);
DISPLAY 1.446809 (-2975 2075);
PAINT GREEN (-2975 2075);
DISPLAY INVISIBLE (-2975 2075);
FORCEPROP 1 LAST HDL_TAP TRUE
J 0
(-2650 1900);
DISPLAY 1.446809 (-2650 1900);
PAINT GREEN (-2650 1900);
DISPLAY INVISIBLE (-2650 1900);
FORCEPROP 1 LAST PATH I53
J 0
(-2977 2025);
DISPLAY 0.872340 (-2977 2025);
PAINT GREEN (-2977 2025);
DISPLAY INVISIBLE (-2977 2025);
FORCEADD TAP..1
(-2975 2075);
FORCEPROP 3 LASTPIN (-3025 2075) SIG_NAME UPI_CPU0_CPU1_P1P1_DN<9>
J 0
(-3015 2085);
DISPLAY 0.659574 (-3015 2085);
PAINT MONO (-3015 2085);
DISPLAY INVISIBLE (-3015 2085);
FORCEPROP 1 LASTPIN (-3025 2075) BN 9
J 0
(-3037 2083);
DISPLAY 0.617021 (-3037 2083);
PAINT PINK (-3037 2083);
FORCEPROP 2 LAST CDS_LIB mstr_standard
J 0
(-2975 2075);
PAINT MONO (-2975 2075);
DISPLAY INVISIBLE (-2975 2075);
FORCEPROP 1 LAST BODY_TYPE PLUMBING
J 0
(-2975 2125);
DISPLAY 1.446809 (-2975 2125);
PAINT GREEN (-2975 2125);
DISPLAY INVISIBLE (-2975 2125);
FORCEPROP 1 LAST HDL_TAP TRUE
J 0
(-2650 1950);
DISPLAY 1.446809 (-2650 1950);
PAINT GREEN (-2650 1950);
DISPLAY INVISIBLE (-2650 1950);
FORCEPROP 1 LAST PATH I54
J 0
(-2977 2075);
DISPLAY 0.872340 (-2977 2075);
PAINT GREEN (-2977 2075);
DISPLAY INVISIBLE (-2977 2075);
FORCEADD TAP..1
(-2975 2125);
FORCEPROP 3 LASTPIN (-3025 2125) SIG_NAME UPI_CPU0_CPU1_P1P1_DN<8>
J 0
(-3015 2135);
DISPLAY 0.659574 (-3015 2135);
PAINT MONO (-3015 2135);
DISPLAY INVISIBLE (-3015 2135);
FORCEPROP 1 LASTPIN (-3025 2125) BN 8
J 0
(-3037 2133);
DISPLAY 0.617021 (-3037 2133);
PAINT PINK (-3037 2133);
FORCEPROP 2 LAST CDS_LIB mstr_standard
J 0
(-2975 2125);
PAINT MONO (-2975 2125);
DISPLAY INVISIBLE (-2975 2125);
FORCEPROP 1 LAST BODY_TYPE PLUMBING
J 0
(-2975 2175);
DISPLAY 1.446809 (-2975 2175);
PAINT GREEN (-2975 2175);
DISPLAY INVISIBLE (-2975 2175);
FORCEPROP 1 LAST HDL_TAP TRUE
J 0
(-2650 2000);
DISPLAY 1.446809 (-2650 2000);
PAINT GREEN (-2650 2000);
DISPLAY INVISIBLE (-2650 2000);
FORCEPROP 1 LAST PATH I55
J 0
(-2977 2125);
DISPLAY 0.872340 (-2977 2125);
PAINT GREEN (-2977 2125);
DISPLAY INVISIBLE (-2977 2125);
FORCEADD TAP..1
(-2975 2175);
FORCEPROP 3 LASTPIN (-3025 2175) SIG_NAME UPI_CPU0_CPU1_P1P1_DN<7>
J 0
(-3015 2185);
DISPLAY 0.659574 (-3015 2185);
PAINT MONO (-3015 2185);
DISPLAY INVISIBLE (-3015 2185);
FORCEPROP 1 LASTPIN (-3025 2175) BN 7
J 0
(-3037 2183);
DISPLAY 0.617021 (-3037 2183);
PAINT PINK (-3037 2183);
FORCEPROP 2 LAST CDS_LIB mstr_standard
J 0
(-2975 2175);
PAINT MONO (-2975 2175);
DISPLAY INVISIBLE (-2975 2175);
FORCEPROP 1 LAST BODY_TYPE PLUMBING
J 0
(-2975 2225);
DISPLAY 1.446809 (-2975 2225);
PAINT GREEN (-2975 2225);
DISPLAY INVISIBLE (-2975 2225);
FORCEPROP 1 LAST HDL_TAP TRUE
J 0
(-2650 2050);
DISPLAY 1.446809 (-2650 2050);
PAINT GREEN (-2650 2050);
DISPLAY INVISIBLE (-2650 2050);
FORCEPROP 1 LAST PATH I56
J 0
(-2977 2175);
DISPLAY 0.872340 (-2977 2175);
PAINT GREEN (-2977 2175);
DISPLAY INVISIBLE (-2977 2175);
FORCEADD TAP..1
(-2975 2225);
FORCEPROP 3 LASTPIN (-3025 2225) SIG_NAME UPI_CPU0_CPU1_P1P1_DN<6>
J 0
(-3015 2235);
DISPLAY 0.659574 (-3015 2235);
PAINT MONO (-3015 2235);
DISPLAY INVISIBLE (-3015 2235);
FORCEPROP 1 LASTPIN (-3025 2225) BN 6
J 0
(-3037 2233);
DISPLAY 0.617021 (-3037 2233);
PAINT PINK (-3037 2233);
FORCEPROP 2 LAST CDS_LIB mstr_standard
J 0
(-2975 2225);
PAINT MONO (-2975 2225);
DISPLAY INVISIBLE (-2975 2225);
FORCEPROP 1 LAST BODY_TYPE PLUMBING
J 0
(-2975 2275);
DISPLAY 1.446809 (-2975 2275);
PAINT GREEN (-2975 2275);
DISPLAY INVISIBLE (-2975 2275);
FORCEPROP 1 LAST HDL_TAP TRUE
J 0
(-2650 2100);
DISPLAY 1.446809 (-2650 2100);
PAINT GREEN (-2650 2100);
DISPLAY INVISIBLE (-2650 2100);
FORCEPROP 1 LAST PATH I57
J 0
(-2977 2225);
DISPLAY 0.872340 (-2977 2225);
PAINT GREEN (-2977 2225);
DISPLAY INVISIBLE (-2977 2225);
FORCEADD TAP..1
(-2975 2275);
FORCEPROP 3 LASTPIN (-3025 2275) SIG_NAME UPI_CPU0_CPU1_P1P1_DN<5>
J 0
(-3015 2285);
DISPLAY 0.659574 (-3015 2285);
PAINT MONO (-3015 2285);
DISPLAY INVISIBLE (-3015 2285);
FORCEPROP 1 LASTPIN (-3025 2275) BN 5
J 0
(-3037 2283);
DISPLAY 0.617021 (-3037 2283);
PAINT PINK (-3037 2283);
FORCEPROP 2 LAST CDS_LIB mstr_standard
J 0
(-2975 2275);
PAINT MONO (-2975 2275);
DISPLAY INVISIBLE (-2975 2275);
FORCEPROP 1 LAST BODY_TYPE PLUMBING
J 0
(-2975 2325);
DISPLAY 1.446809 (-2975 2325);
PAINT GREEN (-2975 2325);
DISPLAY INVISIBLE (-2975 2325);
FORCEPROP 1 LAST HDL_TAP TRUE
J 0
(-2650 2150);
DISPLAY 1.446809 (-2650 2150);
PAINT GREEN (-2650 2150);
DISPLAY INVISIBLE (-2650 2150);
FORCEPROP 1 LAST PATH I58
J 0
(-2977 2275);
DISPLAY 0.872340 (-2977 2275);
PAINT GREEN (-2977 2275);
DISPLAY INVISIBLE (-2977 2275);
FORCEADD TAP..1
(-2975 2325);
FORCEPROP 3 LASTPIN (-3025 2325) SIG_NAME UPI_CPU0_CPU1_P1P1_DN<4>
J 0
(-3015 2335);
DISPLAY 0.659574 (-3015 2335);
PAINT MONO (-3015 2335);
DISPLAY INVISIBLE (-3015 2335);
FORCEPROP 1 LASTPIN (-3025 2325) BN 4
J 0
(-3037 2333);
DISPLAY 0.617021 (-3037 2333);
PAINT PINK (-3037 2333);
FORCEPROP 2 LAST CDS_LIB mstr_standard
J 0
(-2975 2325);
PAINT MONO (-2975 2325);
DISPLAY INVISIBLE (-2975 2325);
FORCEPROP 1 LAST BODY_TYPE PLUMBING
J 0
(-2975 2375);
DISPLAY 1.446809 (-2975 2375);
PAINT GREEN (-2975 2375);
DISPLAY INVISIBLE (-2975 2375);
FORCEPROP 1 LAST HDL_TAP TRUE
J 0
(-2650 2200);
DISPLAY 1.446809 (-2650 2200);
PAINT GREEN (-2650 2200);
DISPLAY INVISIBLE (-2650 2200);
FORCEPROP 1 LAST PATH I59
J 0
(-2977 2325);
DISPLAY 0.872340 (-2977 2325);
PAINT GREEN (-2977 2325);
DISPLAY INVISIBLE (-2977 2325);
FORCEADD TAP..1
R 2
(-5300 1725);
FORCEPROP 3 LASTPIN (-5250 1725) SIG_NAME UPI_CPU1_CPU0_P1P1_DN<16>
J 0
(-5240 1735);
DISPLAY 0.659574 (-5240 1735);
PAINT MONO (-5240 1735);
DISPLAY INVISIBLE (-5240 1735);
FORCEPROP 1 LASTPIN (-5250 1725) BN 16
J 2
(-5238 1733);
DISPLAY 0.617021 (-5238 1733);
PAINT PINK (-5238 1733);
FORCEPROP 2 LAST CDS_LIB mstr_standard
J 0
(-5300 1725);
PAINT MONO (-5300 1725);
DISPLAY INVISIBLE (-5300 1725);
FORCEPROP 1 LAST BODY_TYPE PLUMBING
J 2
(-5300 1775);
DISPLAY 1.446809 (-5300 1775);
PAINT GREEN (-5300 1775);
DISPLAY INVISIBLE (-5300 1775);
FORCEPROP 1 LAST HDL_TAP TRUE
J 2
(-5625 1600);
DISPLAY 1.446809 (-5625 1600);
PAINT GREEN (-5625 1600);
DISPLAY INVISIBLE (-5625 1600);
FORCEPROP 1 LAST PATH I6
J 2
(-5298 1725);
DISPLAY 0.872340 (-5298 1725);
PAINT GREEN (-5298 1725);
DISPLAY INVISIBLE (-5298 1725);
FORCEADD TAP..1
(-2975 2375);
FORCEPROP 3 LASTPIN (-3025 2375) SIG_NAME UPI_CPU0_CPU1_P1P1_DN<3>
J 0
(-3015 2385);
DISPLAY 0.659574 (-3015 2385);
PAINT MONO (-3015 2385);
DISPLAY INVISIBLE (-3015 2385);
FORCEPROP 1 LASTPIN (-3025 2375) BN 3
J 0
(-3037 2383);
DISPLAY 0.617021 (-3037 2383);
PAINT PINK (-3037 2383);
FORCEPROP 2 LAST CDS_LIB mstr_standard
J 0
(-2975 2375);
PAINT MONO (-2975 2375);
DISPLAY INVISIBLE (-2975 2375);
FORCEPROP 1 LAST BODY_TYPE PLUMBING
J 0
(-2975 2425);
DISPLAY 1.446809 (-2975 2425);
PAINT GREEN (-2975 2425);
DISPLAY INVISIBLE (-2975 2425);
FORCEPROP 1 LAST HDL_TAP TRUE
J 0
(-2650 2250);
DISPLAY 1.446809 (-2650 2250);
PAINT GREEN (-2650 2250);
DISPLAY INVISIBLE (-2650 2250);
FORCEPROP 1 LAST PATH I60
J 0
(-2977 2375);
DISPLAY 0.872340 (-2977 2375);
PAINT GREEN (-2977 2375);
DISPLAY INVISIBLE (-2977 2375);
FORCEADD TAP..1
(-2975 2425);
FORCEPROP 3 LASTPIN (-3025 2425) SIG_NAME UPI_CPU0_CPU1_P1P1_DN<2>
J 0
(-3015 2435);
DISPLAY 0.659574 (-3015 2435);
PAINT MONO (-3015 2435);
DISPLAY INVISIBLE (-3015 2435);
FORCEPROP 1 LASTPIN (-3025 2425) BN 2
J 0
(-3037 2433);
DISPLAY 0.617021 (-3037 2433);
PAINT PINK (-3037 2433);
FORCEPROP 2 LAST CDS_LIB mstr_standard
J 0
(-2975 2425);
PAINT MONO (-2975 2425);
DISPLAY INVISIBLE (-2975 2425);
FORCEPROP 1 LAST BODY_TYPE PLUMBING
J 0
(-2975 2475);
DISPLAY 1.446809 (-2975 2475);
PAINT GREEN (-2975 2475);
DISPLAY INVISIBLE (-2975 2475);
FORCEPROP 1 LAST HDL_TAP TRUE
J 0
(-2650 2300);
DISPLAY 1.446809 (-2650 2300);
PAINT GREEN (-2650 2300);
DISPLAY INVISIBLE (-2650 2300);
FORCEPROP 1 LAST PATH I61
J 0
(-2977 2425);
DISPLAY 0.872340 (-2977 2425);
PAINT GREEN (-2977 2425);
DISPLAY INVISIBLE (-2977 2425);
FORCEADD TAP..1
(-2975 2475);
FORCEPROP 3 LASTPIN (-3025 2475) SIG_NAME UPI_CPU0_CPU1_P1P1_DN<1>
J 0
(-3015 2485);
DISPLAY 0.659574 (-3015 2485);
PAINT MONO (-3015 2485);
DISPLAY INVISIBLE (-3015 2485);
FORCEPROP 1 LASTPIN (-3025 2475) BN 1
J 0
(-3037 2483);
DISPLAY 0.617021 (-3037 2483);
PAINT PINK (-3037 2483);
FORCEPROP 2 LAST CDS_LIB mstr_standard
J 0
(-2975 2475);
PAINT MONO (-2975 2475);
DISPLAY INVISIBLE (-2975 2475);
FORCEPROP 1 LAST BODY_TYPE PLUMBING
J 0
(-2975 2525);
DISPLAY 1.446809 (-2975 2525);
PAINT GREEN (-2975 2525);
DISPLAY INVISIBLE (-2975 2525);
FORCEPROP 1 LAST HDL_TAP TRUE
J 0
(-2650 2350);
DISPLAY 1.446809 (-2650 2350);
PAINT GREEN (-2650 2350);
DISPLAY INVISIBLE (-2650 2350);
FORCEPROP 1 LAST PATH I62
J 0
(-2977 2475);
DISPLAY 0.872340 (-2977 2475);
PAINT GREEN (-2977 2475);
DISPLAY INVISIBLE (-2977 2475);
FORCEADD TAP..1
(-2975 2525);
FORCEPROP 3 LASTPIN (-3025 2525) SIG_NAME UPI_CPU0_CPU1_P1P1_DN<0>
J 0
(-3015 2535);
DISPLAY 0.659574 (-3015 2535);
PAINT MONO (-3015 2535);
DISPLAY INVISIBLE (-3015 2535);
FORCEPROP 1 LASTPIN (-3025 2525) BN 0
J 0
(-3037 2533);
DISPLAY 0.617021 (-3037 2533);
PAINT PINK (-3037 2533);
FORCEPROP 2 LAST CDS_LIB mstr_standard
J 0
(-2975 2525);
PAINT MONO (-2975 2525);
DISPLAY INVISIBLE (-2975 2525);
FORCEPROP 1 LAST BODY_TYPE PLUMBING
J 0
(-2975 2575);
DISPLAY 1.446809 (-2975 2575);
PAINT GREEN (-2975 2575);
DISPLAY INVISIBLE (-2975 2575);
FORCEPROP 1 LAST HDL_TAP TRUE
J 0
(-2650 2400);
DISPLAY 1.446809 (-2650 2400);
PAINT GREEN (-2650 2400);
DISPLAY INVISIBLE (-2650 2400);
FORCEPROP 1 LAST PATH I63
J 0
(-2977 2525);
DISPLAY 0.872340 (-2977 2525);
PAINT GREEN (-2977 2525);
DISPLAY INVISIBLE (-2977 2525);
FORCEADD TAP..1
(-2975 2625);
FORCEPROP 3 LASTPIN (-3025 2625) SIG_NAME UPI_CPU0_CPU1_P1P1_DP<19>
J 0
(-3015 2635);
DISPLAY 0.659574 (-3015 2635);
PAINT MONO (-3015 2635);
DISPLAY INVISIBLE (-3015 2635);
FORCEPROP 1 LASTPIN (-3025 2625) BN 19
J 0
(-3037 2633);
DISPLAY 0.617021 (-3037 2633);
PAINT PINK (-3037 2633);
FORCEPROP 2 LAST CDS_LIB mstr_standard
J 0
(-2975 2625);
PAINT MONO (-2975 2625);
DISPLAY INVISIBLE (-2975 2625);
FORCEPROP 1 LAST BODY_TYPE PLUMBING
J 0
(-2975 2675);
DISPLAY 1.446809 (-2975 2675);
PAINT GREEN (-2975 2675);
DISPLAY INVISIBLE (-2975 2675);
FORCEPROP 1 LAST HDL_TAP TRUE
J 0
(-2650 2500);
DISPLAY 1.446809 (-2650 2500);
PAINT GREEN (-2650 2500);
DISPLAY INVISIBLE (-2650 2500);
FORCEPROP 1 LAST PATH I64
J 0
(-2977 2625);
DISPLAY 0.872340 (-2977 2625);
PAINT GREEN (-2977 2625);
DISPLAY INVISIBLE (-2977 2625);
FORCEADD TAP..1
(-2975 2675);
FORCEPROP 3 LASTPIN (-3025 2675) SIG_NAME UPI_CPU0_CPU1_P1P1_DP<18>
J 0
(-3015 2685);
DISPLAY 0.659574 (-3015 2685);
PAINT MONO (-3015 2685);
DISPLAY INVISIBLE (-3015 2685);
FORCEPROP 1 LASTPIN (-3025 2675) BN 18
J 0
(-3037 2683);
DISPLAY 0.617021 (-3037 2683);
PAINT PINK (-3037 2683);
FORCEPROP 2 LAST CDS_LIB mstr_standard
J 0
(-2975 2675);
PAINT MONO (-2975 2675);
DISPLAY INVISIBLE (-2975 2675);
FORCEPROP 1 LAST BODY_TYPE PLUMBING
J 0
(-2975 2725);
DISPLAY 1.446809 (-2975 2725);
PAINT GREEN (-2975 2725);
DISPLAY INVISIBLE (-2975 2725);
FORCEPROP 1 LAST HDL_TAP TRUE
J 0
(-2650 2550);
DISPLAY 1.446809 (-2650 2550);
PAINT GREEN (-2650 2550);
DISPLAY INVISIBLE (-2650 2550);
FORCEPROP 1 LAST PATH I65
J 0
(-2977 2675);
DISPLAY 0.872340 (-2977 2675);
PAINT GREEN (-2977 2675);
DISPLAY INVISIBLE (-2977 2675);
FORCEADD TAP..1
(-2975 2725);
FORCEPROP 3 LASTPIN (-3025 2725) SIG_NAME UPI_CPU0_CPU1_P1P1_DP<17>
J 0
(-3015 2735);
DISPLAY 0.659574 (-3015 2735);
PAINT MONO (-3015 2735);
DISPLAY INVISIBLE (-3015 2735);
FORCEPROP 1 LASTPIN (-3025 2725) BN 17
J 0
(-3037 2733);
DISPLAY 0.617021 (-3037 2733);
PAINT PINK (-3037 2733);
FORCEPROP 2 LAST CDS_LIB mstr_standard
J 0
(-2975 2725);
PAINT MONO (-2975 2725);
DISPLAY INVISIBLE (-2975 2725);
FORCEPROP 1 LAST BODY_TYPE PLUMBING
J 0
(-2975 2775);
DISPLAY 1.446809 (-2975 2775);
PAINT GREEN (-2975 2775);
DISPLAY INVISIBLE (-2975 2775);
FORCEPROP 1 LAST HDL_TAP TRUE
J 0
(-2650 2600);
DISPLAY 1.446809 (-2650 2600);
PAINT GREEN (-2650 2600);
DISPLAY INVISIBLE (-2650 2600);
FORCEPROP 1 LAST PATH I66
J 0
(-2977 2725);
DISPLAY 0.872340 (-2977 2725);
PAINT GREEN (-2977 2725);
DISPLAY INVISIBLE (-2977 2725);
FORCEADD TAP..1
(-2975 2775);
FORCEPROP 3 LASTPIN (-3025 2775) SIG_NAME UPI_CPU0_CPU1_P1P1_DP<16>
J 0
(-3015 2785);
DISPLAY 0.659574 (-3015 2785);
PAINT MONO (-3015 2785);
DISPLAY INVISIBLE (-3015 2785);
FORCEPROP 1 LASTPIN (-3025 2775) BN 16
J 0
(-3037 2783);
DISPLAY 0.617021 (-3037 2783);
PAINT PINK (-3037 2783);
FORCEPROP 2 LAST CDS_LIB mstr_standard
J 0
(-2975 2775);
PAINT MONO (-2975 2775);
DISPLAY INVISIBLE (-2975 2775);
FORCEPROP 1 LAST BODY_TYPE PLUMBING
J 0
(-2975 2825);
DISPLAY 1.446809 (-2975 2825);
PAINT GREEN (-2975 2825);
DISPLAY INVISIBLE (-2975 2825);
FORCEPROP 1 LAST HDL_TAP TRUE
J 0
(-2650 2650);
DISPLAY 1.446809 (-2650 2650);
PAINT GREEN (-2650 2650);
DISPLAY INVISIBLE (-2650 2650);
FORCEPROP 1 LAST PATH I67
J 0
(-2977 2775);
DISPLAY 0.872340 (-2977 2775);
PAINT GREEN (-2977 2775);
DISPLAY INVISIBLE (-2977 2775);
FORCEADD TAP..1
(-2975 2825);
FORCEPROP 3 LASTPIN (-3025 2825) SIG_NAME UPI_CPU0_CPU1_P1P1_DP<15>
J 0
(-3015 2835);
DISPLAY 0.659574 (-3015 2835);
PAINT MONO (-3015 2835);
DISPLAY INVISIBLE (-3015 2835);
FORCEPROP 1 LASTPIN (-3025 2825) BN 15
J 0
(-3037 2833);
DISPLAY 0.617021 (-3037 2833);
PAINT PINK (-3037 2833);
FORCEPROP 2 LAST CDS_LIB mstr_standard
J 0
(-2975 2825);
PAINT MONO (-2975 2825);
DISPLAY INVISIBLE (-2975 2825);
FORCEPROP 1 LAST BODY_TYPE PLUMBING
J 0
(-2975 2875);
DISPLAY 1.446809 (-2975 2875);
PAINT GREEN (-2975 2875);
DISPLAY INVISIBLE (-2975 2875);
FORCEPROP 1 LAST HDL_TAP TRUE
J 0
(-2650 2700);
DISPLAY 1.446809 (-2650 2700);
PAINT GREEN (-2650 2700);
DISPLAY INVISIBLE (-2650 2700);
FORCEPROP 1 LAST PATH I68
J 0
(-2977 2825);
DISPLAY 0.872340 (-2977 2825);
PAINT GREEN (-2977 2825);
DISPLAY INVISIBLE (-2977 2825);
FORCEADD TAP..1
(-2975 2875);
FORCEPROP 3 LASTPIN (-3025 2875) SIG_NAME UPI_CPU0_CPU1_P1P1_DP<14>
J 0
(-3015 2885);
DISPLAY 0.659574 (-3015 2885);
PAINT MONO (-3015 2885);
DISPLAY INVISIBLE (-3015 2885);
FORCEPROP 1 LASTPIN (-3025 2875) BN 14
J 0
(-3037 2883);
DISPLAY 0.617021 (-3037 2883);
PAINT PINK (-3037 2883);
FORCEPROP 2 LAST CDS_LIB mstr_standard
J 0
(-2975 2875);
PAINT MONO (-2975 2875);
DISPLAY INVISIBLE (-2975 2875);
FORCEPROP 1 LAST BODY_TYPE PLUMBING
J 0
(-2975 2925);
DISPLAY 1.446809 (-2975 2925);
PAINT GREEN (-2975 2925);
DISPLAY INVISIBLE (-2975 2925);
FORCEPROP 1 LAST HDL_TAP TRUE
J 0
(-2650 2750);
DISPLAY 1.446809 (-2650 2750);
PAINT GREEN (-2650 2750);
DISPLAY INVISIBLE (-2650 2750);
FORCEPROP 1 LAST PATH I69
J 0
(-2977 2875);
DISPLAY 0.872340 (-2977 2875);
PAINT GREEN (-2977 2875);
DISPLAY INVISIBLE (-2977 2875);
FORCEADD TAP..1
R 2
(-5300 1775);
FORCEPROP 3 LASTPIN (-5250 1775) SIG_NAME UPI_CPU1_CPU0_P1P1_DN<15>
J 0
(-5240 1785);
DISPLAY 0.659574 (-5240 1785);
PAINT MONO (-5240 1785);
DISPLAY INVISIBLE (-5240 1785);
FORCEPROP 1 LASTPIN (-5250 1775) BN 15
J 2
(-5238 1783);
DISPLAY 0.617021 (-5238 1783);
PAINT PINK (-5238 1783);
FORCEPROP 2 LAST CDS_LIB mstr_standard
J 0
(-5300 1775);
PAINT MONO (-5300 1775);
DISPLAY INVISIBLE (-5300 1775);
FORCEPROP 1 LAST BODY_TYPE PLUMBING
J 2
(-5300 1825);
DISPLAY 1.446809 (-5300 1825);
PAINT GREEN (-5300 1825);
DISPLAY INVISIBLE (-5300 1825);
FORCEPROP 1 LAST HDL_TAP TRUE
J 2
(-5625 1650);
DISPLAY 1.446809 (-5625 1650);
PAINT GREEN (-5625 1650);
DISPLAY INVISIBLE (-5625 1650);
FORCEPROP 1 LAST PATH I7
J 2
(-5298 1775);
DISPLAY 0.872340 (-5298 1775);
PAINT GREEN (-5298 1775);
DISPLAY INVISIBLE (-5298 1775);
FORCEADD TAP..1
(-2975 2925);
FORCEPROP 3 LASTPIN (-3025 2925) SIG_NAME UPI_CPU0_CPU1_P1P1_DP<13>
J 0
(-3015 2935);
DISPLAY 0.659574 (-3015 2935);
PAINT MONO (-3015 2935);
DISPLAY INVISIBLE (-3015 2935);
FORCEPROP 1 LASTPIN (-3025 2925) BN 13
J 0
(-3037 2933);
DISPLAY 0.617021 (-3037 2933);
PAINT PINK (-3037 2933);
FORCEPROP 2 LAST CDS_LIB mstr_standard
J 0
(-2975 2925);
PAINT MONO (-2975 2925);
DISPLAY INVISIBLE (-2975 2925);
FORCEPROP 1 LAST BODY_TYPE PLUMBING
J 0
(-2975 2975);
DISPLAY 1.446809 (-2975 2975);
PAINT GREEN (-2975 2975);
DISPLAY INVISIBLE (-2975 2975);
FORCEPROP 1 LAST HDL_TAP TRUE
J 0
(-2650 2800);
DISPLAY 1.446809 (-2650 2800);
PAINT GREEN (-2650 2800);
DISPLAY INVISIBLE (-2650 2800);
FORCEPROP 1 LAST PATH I70
J 0
(-2977 2925);
DISPLAY 0.872340 (-2977 2925);
PAINT GREEN (-2977 2925);
DISPLAY INVISIBLE (-2977 2925);
FORCEADD TAP..1
(-2975 2975);
FORCEPROP 3 LASTPIN (-3025 2975) SIG_NAME UPI_CPU0_CPU1_P1P1_DP<12>
J 0
(-3015 2985);
DISPLAY 0.659574 (-3015 2985);
PAINT MONO (-3015 2985);
DISPLAY INVISIBLE (-3015 2985);
FORCEPROP 1 LASTPIN (-3025 2975) BN 12
J 0
(-3037 2983);
DISPLAY 0.617021 (-3037 2983);
PAINT PINK (-3037 2983);
FORCEPROP 2 LAST CDS_LIB mstr_standard
J 0
(-2975 2975);
PAINT MONO (-2975 2975);
DISPLAY INVISIBLE (-2975 2975);
FORCEPROP 1 LAST BODY_TYPE PLUMBING
J 0
(-2975 3025);
DISPLAY 1.446809 (-2975 3025);
PAINT GREEN (-2975 3025);
DISPLAY INVISIBLE (-2975 3025);
FORCEPROP 1 LAST HDL_TAP TRUE
J 0
(-2650 2850);
DISPLAY 1.446809 (-2650 2850);
PAINT GREEN (-2650 2850);
DISPLAY INVISIBLE (-2650 2850);
FORCEPROP 1 LAST PATH I71
J 0
(-2977 2975);
DISPLAY 0.872340 (-2977 2975);
PAINT GREEN (-2977 2975);
DISPLAY INVISIBLE (-2977 2975);
FORCEADD TAP..1
(-2975 3025);
FORCEPROP 3 LASTPIN (-3025 3025) SIG_NAME UPI_CPU0_CPU1_P1P1_DP<11>
J 0
(-3015 3035);
DISPLAY 0.659574 (-3015 3035);
PAINT MONO (-3015 3035);
DISPLAY INVISIBLE (-3015 3035);
FORCEPROP 1 LASTPIN (-3025 3025) BN 11
J 0
(-3037 3033);
DISPLAY 0.617021 (-3037 3033);
PAINT PINK (-3037 3033);
FORCEPROP 2 LAST CDS_LIB mstr_standard
J 0
(-2975 3025);
PAINT MONO (-2975 3025);
DISPLAY INVISIBLE (-2975 3025);
FORCEPROP 1 LAST BODY_TYPE PLUMBING
J 0
(-2975 3075);
DISPLAY 1.446809 (-2975 3075);
PAINT GREEN (-2975 3075);
DISPLAY INVISIBLE (-2975 3075);
FORCEPROP 1 LAST HDL_TAP TRUE
J 0
(-2650 2900);
DISPLAY 1.446809 (-2650 2900);
PAINT GREEN (-2650 2900);
DISPLAY INVISIBLE (-2650 2900);
FORCEPROP 1 LAST PATH I72
J 0
(-2977 3025);
DISPLAY 0.872340 (-2977 3025);
PAINT GREEN (-2977 3025);
DISPLAY INVISIBLE (-2977 3025);
FORCEADD TAP..1
(-2975 3075);
FORCEPROP 3 LASTPIN (-3025 3075) SIG_NAME UPI_CPU0_CPU1_P1P1_DP<10>
J 0
(-3015 3085);
DISPLAY 0.659574 (-3015 3085);
PAINT MONO (-3015 3085);
DISPLAY INVISIBLE (-3015 3085);
FORCEPROP 1 LASTPIN (-3025 3075) BN 10
J 0
(-3037 3083);
DISPLAY 0.617021 (-3037 3083);
PAINT PINK (-3037 3083);
FORCEPROP 2 LAST CDS_LIB mstr_standard
J 0
(-2975 3075);
PAINT MONO (-2975 3075);
DISPLAY INVISIBLE (-2975 3075);
FORCEPROP 1 LAST BODY_TYPE PLUMBING
J 0
(-2975 3125);
DISPLAY 1.446809 (-2975 3125);
PAINT GREEN (-2975 3125);
DISPLAY INVISIBLE (-2975 3125);
FORCEPROP 1 LAST HDL_TAP TRUE
J 0
(-2650 2950);
DISPLAY 1.446809 (-2650 2950);
PAINT GREEN (-2650 2950);
DISPLAY INVISIBLE (-2650 2950);
FORCEPROP 1 LAST PATH I73
J 0
(-2977 3075);
DISPLAY 0.872340 (-2977 3075);
PAINT GREEN (-2977 3075);
DISPLAY INVISIBLE (-2977 3075);
FORCEADD TAP..1
(-2975 3125);
FORCEPROP 3 LASTPIN (-3025 3125) SIG_NAME UPI_CPU0_CPU1_P1P1_DP<9>
J 0
(-3015 3135);
DISPLAY 0.659574 (-3015 3135);
PAINT MONO (-3015 3135);
DISPLAY INVISIBLE (-3015 3135);
FORCEPROP 1 LASTPIN (-3025 3125) BN 9
J 0
(-3037 3133);
DISPLAY 0.617021 (-3037 3133);
PAINT PINK (-3037 3133);
FORCEPROP 2 LAST CDS_LIB mstr_standard
J 0
(-2975 3125);
PAINT MONO (-2975 3125);
DISPLAY INVISIBLE (-2975 3125);
FORCEPROP 1 LAST BODY_TYPE PLUMBING
J 0
(-2975 3175);
DISPLAY 1.446809 (-2975 3175);
PAINT GREEN (-2975 3175);
DISPLAY INVISIBLE (-2975 3175);
FORCEPROP 1 LAST HDL_TAP TRUE
J 0
(-2650 3000);
DISPLAY 1.446809 (-2650 3000);
PAINT GREEN (-2650 3000);
DISPLAY INVISIBLE (-2650 3000);
FORCEPROP 1 LAST PATH I74
J 0
(-2977 3125);
DISPLAY 0.872340 (-2977 3125);
PAINT GREEN (-2977 3125);
DISPLAY INVISIBLE (-2977 3125);
FORCEADD TAP..1
(-2975 3225);
FORCEPROP 3 LASTPIN (-3025 3225) SIG_NAME UPI_CPU0_CPU1_P1P1_DP<7>
J 0
(-3015 3235);
DISPLAY 0.659574 (-3015 3235);
PAINT MONO (-3015 3235);
DISPLAY INVISIBLE (-3015 3235);
FORCEPROP 1 LASTPIN (-3025 3225) BN 7
J 0
(-3037 3233);
DISPLAY 0.617021 (-3037 3233);
PAINT PINK (-3037 3233);
FORCEPROP 2 LAST CDS_LIB mstr_standard
J 0
(-2975 3225);
PAINT MONO (-2975 3225);
DISPLAY INVISIBLE (-2975 3225);
FORCEPROP 1 LAST BODY_TYPE PLUMBING
J 0
(-2975 3275);
DISPLAY 1.446809 (-2975 3275);
PAINT GREEN (-2975 3275);
DISPLAY INVISIBLE (-2975 3275);
FORCEPROP 1 LAST HDL_TAP TRUE
J 0
(-2650 3100);
DISPLAY 1.446809 (-2650 3100);
PAINT GREEN (-2650 3100);
DISPLAY INVISIBLE (-2650 3100);
FORCEPROP 1 LAST PATH I75
J 0
(-2977 3225);
DISPLAY 0.872340 (-2977 3225);
PAINT GREEN (-2977 3225);
DISPLAY INVISIBLE (-2977 3225);
FORCEADD TAP..1
(-2975 3175);
FORCEPROP 3 LASTPIN (-3025 3175) SIG_NAME UPI_CPU0_CPU1_P1P1_DP<8>
J 0
(-3015 3185);
DISPLAY 0.659574 (-3015 3185);
PAINT MONO (-3015 3185);
DISPLAY INVISIBLE (-3015 3185);
FORCEPROP 1 LASTPIN (-3025 3175) BN 8
J 0
(-3037 3183);
DISPLAY 0.617021 (-3037 3183);
PAINT PINK (-3037 3183);
FORCEPROP 2 LAST CDS_LIB mstr_standard
J 0
(-2975 3175);
PAINT MONO (-2975 3175);
DISPLAY INVISIBLE (-2975 3175);
FORCEPROP 1 LAST BODY_TYPE PLUMBING
J 0
(-2975 3225);
DISPLAY 1.446809 (-2975 3225);
PAINT GREEN (-2975 3225);
DISPLAY INVISIBLE (-2975 3225);
FORCEPROP 1 LAST HDL_TAP TRUE
J 0
(-2650 3050);
DISPLAY 1.446809 (-2650 3050);
PAINT GREEN (-2650 3050);
DISPLAY INVISIBLE (-2650 3050);
FORCEPROP 1 LAST PATH I76
J 0
(-2977 3175);
DISPLAY 0.872340 (-2977 3175);
PAINT GREEN (-2977 3175);
DISPLAY INVISIBLE (-2977 3175);
FORCEADD TAP..1
(-2975 3275);
FORCEPROP 3 LASTPIN (-3025 3275) SIG_NAME UPI_CPU0_CPU1_P1P1_DP<6>
J 0
(-3015 3285);
DISPLAY 0.659574 (-3015 3285);
PAINT MONO (-3015 3285);
DISPLAY INVISIBLE (-3015 3285);
FORCEPROP 1 LASTPIN (-3025 3275) BN 6
J 0
(-3037 3283);
DISPLAY 0.617021 (-3037 3283);
PAINT PINK (-3037 3283);
FORCEPROP 2 LAST CDS_LIB mstr_standard
J 0
(-2975 3275);
PAINT MONO (-2975 3275);
DISPLAY INVISIBLE (-2975 3275);
FORCEPROP 1 LAST BODY_TYPE PLUMBING
J 0
(-2975 3325);
DISPLAY 1.446809 (-2975 3325);
PAINT GREEN (-2975 3325);
DISPLAY INVISIBLE (-2975 3325);
FORCEPROP 1 LAST HDL_TAP TRUE
J 0
(-2650 3150);
DISPLAY 1.446809 (-2650 3150);
PAINT GREEN (-2650 3150);
DISPLAY INVISIBLE (-2650 3150);
FORCEPROP 1 LAST PATH I77
J 0
(-2977 3275);
DISPLAY 0.872340 (-2977 3275);
PAINT GREEN (-2977 3275);
DISPLAY INVISIBLE (-2977 3275);
FORCEADD TAP..1
(-2975 3325);
FORCEPROP 3 LASTPIN (-3025 3325) SIG_NAME UPI_CPU0_CPU1_P1P1_DP<5>
J 0
(-3015 3335);
DISPLAY 0.659574 (-3015 3335);
PAINT MONO (-3015 3335);
DISPLAY INVISIBLE (-3015 3335);
FORCEPROP 1 LASTPIN (-3025 3325) BN 5
J 0
(-3037 3333);
DISPLAY 0.617021 (-3037 3333);
PAINT PINK (-3037 3333);
FORCEPROP 2 LAST CDS_LIB mstr_standard
J 0
(-2975 3325);
PAINT MONO (-2975 3325);
DISPLAY INVISIBLE (-2975 3325);
FORCEPROP 1 LAST BODY_TYPE PLUMBING
J 0
(-2975 3375);
DISPLAY 1.446809 (-2975 3375);
PAINT GREEN (-2975 3375);
DISPLAY INVISIBLE (-2975 3375);
FORCEPROP 1 LAST HDL_TAP TRUE
J 0
(-2650 3200);
DISPLAY 1.446809 (-2650 3200);
PAINT GREEN (-2650 3200);
DISPLAY INVISIBLE (-2650 3200);
FORCEPROP 1 LAST PATH I78
J 0
(-2977 3325);
DISPLAY 0.872340 (-2977 3325);
PAINT GREEN (-2977 3325);
DISPLAY INVISIBLE (-2977 3325);
FORCEADD TAP..1
(-2975 3375);
FORCEPROP 3 LASTPIN (-3025 3375) SIG_NAME UPI_CPU0_CPU1_P1P1_DP<4>
J 0
(-3015 3385);
DISPLAY 0.659574 (-3015 3385);
PAINT MONO (-3015 3385);
DISPLAY INVISIBLE (-3015 3385);
FORCEPROP 1 LASTPIN (-3025 3375) BN 4
J 0
(-3037 3383);
DISPLAY 0.617021 (-3037 3383);
PAINT PINK (-3037 3383);
FORCEPROP 2 LAST CDS_LIB mstr_standard
J 0
(-2975 3375);
PAINT MONO (-2975 3375);
DISPLAY INVISIBLE (-2975 3375);
FORCEPROP 1 LAST BODY_TYPE PLUMBING
J 0
(-2975 3425);
DISPLAY 1.446809 (-2975 3425);
PAINT GREEN (-2975 3425);
DISPLAY INVISIBLE (-2975 3425);
FORCEPROP 1 LAST HDL_TAP TRUE
J 0
(-2650 3250);
DISPLAY 1.446809 (-2650 3250);
PAINT GREEN (-2650 3250);
DISPLAY INVISIBLE (-2650 3250);
FORCEPROP 1 LAST PATH I79
J 0
(-2977 3375);
DISPLAY 0.872340 (-2977 3375);
PAINT GREEN (-2977 3375);
DISPLAY INVISIBLE (-2977 3375);
FORCEADD TAP..1
(-2975 3475);
FORCEPROP 3 LASTPIN (-3025 3475) SIG_NAME UPI_CPU0_CPU1_P1P1_DP<2>
J 0
(-3015 3485);
DISPLAY 0.659574 (-3015 3485);
PAINT MONO (-3015 3485);
DISPLAY INVISIBLE (-3015 3485);
FORCEPROP 1 LASTPIN (-3025 3475) BN 2
J 0
(-3037 3483);
DISPLAY 0.617021 (-3037 3483);
PAINT PINK (-3037 3483);
FORCEPROP 2 LAST CDS_LIB mstr_standard
J 0
(-2975 3475);
PAINT MONO (-2975 3475);
DISPLAY INVISIBLE (-2975 3475);
FORCEPROP 1 LAST BODY_TYPE PLUMBING
J 0
(-2975 3525);
DISPLAY 1.446809 (-2975 3525);
PAINT GREEN (-2975 3525);
DISPLAY INVISIBLE (-2975 3525);
FORCEPROP 1 LAST HDL_TAP TRUE
J 0
(-2650 3350);
DISPLAY 1.446809 (-2650 3350);
PAINT GREEN (-2650 3350);
DISPLAY INVISIBLE (-2650 3350);
FORCEPROP 1 LAST PATH I80
J 0
(-2977 3475);
DISPLAY 0.872340 (-2977 3475);
PAINT GREEN (-2977 3475);
DISPLAY INVISIBLE (-2977 3475);
FORCEADD TAP..1
(-2975 3425);
FORCEPROP 3 LASTPIN (-3025 3425) SIG_NAME UPI_CPU0_CPU1_P1P1_DP<3>
J 0
(-3015 3435);
DISPLAY 0.659574 (-3015 3435);
PAINT MONO (-3015 3435);
DISPLAY INVISIBLE (-3015 3435);
FORCEPROP 1 LASTPIN (-3025 3425) BN 3
J 0
(-3037 3433);
DISPLAY 0.617021 (-3037 3433);
PAINT PINK (-3037 3433);
FORCEPROP 2 LAST CDS_LIB mstr_standard
J 0
(-2975 3425);
PAINT MONO (-2975 3425);
DISPLAY INVISIBLE (-2975 3425);
FORCEPROP 1 LAST BODY_TYPE PLUMBING
J 0
(-2975 3475);
DISPLAY 1.446809 (-2975 3475);
PAINT GREEN (-2975 3475);
DISPLAY INVISIBLE (-2975 3475);
FORCEPROP 1 LAST HDL_TAP TRUE
J 0
(-2650 3300);
DISPLAY 1.446809 (-2650 3300);
PAINT GREEN (-2650 3300);
DISPLAY INVISIBLE (-2650 3300);
FORCEPROP 1 LAST PATH I81
J 0
(-2977 3425);
DISPLAY 0.872340 (-2977 3425);
PAINT GREEN (-2977 3425);
DISPLAY INVISIBLE (-2977 3425);
FORCEADD TAP..1
(-2975 3525);
FORCEPROP 3 LASTPIN (-3025 3525) SIG_NAME UPI_CPU0_CPU1_P1P1_DP<1>
J 0
(-3015 3535);
DISPLAY 0.659574 (-3015 3535);
PAINT MONO (-3015 3535);
DISPLAY INVISIBLE (-3015 3535);
FORCEPROP 1 LASTPIN (-3025 3525) BN 1
J 0
(-3037 3533);
DISPLAY 0.617021 (-3037 3533);
PAINT PINK (-3037 3533);
FORCEPROP 2 LAST CDS_LIB mstr_standard
J 0
(-2975 3525);
PAINT MONO (-2975 3525);
DISPLAY INVISIBLE (-2975 3525);
FORCEPROP 1 LAST BODY_TYPE PLUMBING
J 0
(-2975 3575);
DISPLAY 1.446809 (-2975 3575);
PAINT GREEN (-2975 3575);
DISPLAY INVISIBLE (-2975 3575);
FORCEPROP 1 LAST HDL_TAP TRUE
J 0
(-2650 3400);
DISPLAY 1.446809 (-2650 3400);
PAINT GREEN (-2650 3400);
DISPLAY INVISIBLE (-2650 3400);
FORCEPROP 1 LAST PATH I82
J 0
(-2977 3525);
DISPLAY 0.872340 (-2977 3525);
PAINT GREEN (-2977 3525);
DISPLAY INVISIBLE (-2977 3525);
FORCEADD TAP..1
(-2975 3575);
FORCEPROP 3 LASTPIN (-3025 3575) SIG_NAME UPI_CPU0_CPU1_P1P1_DP<0>
J 0
(-3015 3585);
DISPLAY 0.659574 (-3015 3585);
PAINT MONO (-3015 3585);
DISPLAY INVISIBLE (-3015 3585);
FORCEPROP 1 LASTPIN (-3025 3575) BN 0
J 0
(-3037 3583);
DISPLAY 0.617021 (-3037 3583);
PAINT PINK (-3037 3583);
FORCEPROP 2 LAST CDS_LIB mstr_standard
J 2
(-2975 3575);
PAINT MONO (-2975 3575);
DISPLAY INVISIBLE (-2975 3575);
FORCEPROP 1 LAST BODY_TYPE PLUMBING
J 0
(-2975 3625);
DISPLAY 1.446809 (-2975 3625);
PAINT GREEN (-2975 3625);
DISPLAY INVISIBLE (-2975 3625);
FORCEPROP 1 LAST HDL_TAP TRUE
J 0
(-2650 3450);
DISPLAY 1.446809 (-2650 3450);
PAINT GREEN (-2650 3450);
DISPLAY INVISIBLE (-2650 3450);
FORCEPROP 1 LAST PATH I83
J 0
(-2977 3575);
DISPLAY 0.872340 (-2977 3575);
PAINT GREEN (-2977 3575);
DISPLAY INVISIBLE (-2977 3575);
FORCEADD OFFPAGE..2
(-1775 2575);
FORCEPROP 2 LAST $XR0 68 
J 0
(-1586 2575);
DISPLAY 0.638298 (-1586 2575);
PAINT MONO (-1586 2575);
FORCEPROP 2 LAST CDS_LIB mstr_standard
J 0
(-1775 2575);
PAINT MONO (-1775 2575);
DISPLAY INVISIBLE (-1775 2575);
FORCEPROP 1 LAST OFFPAGE TRUE
J 0
(-1450 2450);
DISPLAY 1.170213 (-1450 2450);
PAINT GREEN (-1450 2450);
DISPLAY INVISIBLE (-1450 2450);
FORCEPROP 1 LAST COMMENT_BODY TRUE
J 0
(-1820 2480);
DISPLAY 1.170213 (-1820 2480);
PAINT GREEN (-1820 2480);
DISPLAY INVISIBLE (-1820 2480);
FORCEPROP 2 LAST PATH I84
J 0
(-1600 2650);
DISPLAY 1.021277 (-1600 2650);
PAINT ORANGE (-1600 2650);
DISPLAY INVISIBLE (-1600 2650);
FORCEADD OFFPAGE..2
(-1775 3625);
FORCEPROP 2 LAST $XR0 68 
J 0
(-1586 3625);
DISPLAY 0.638298 (-1586 3625);
PAINT MONO (-1586 3625);
FORCEPROP 2 LAST CDS_LIB mstr_standard
J 0
(-1775 3625);
PAINT MONO (-1775 3625);
DISPLAY INVISIBLE (-1775 3625);
FORCEPROP 1 LAST OFFPAGE TRUE
J 0
(-1450 3500);
DISPLAY 1.170213 (-1450 3500);
PAINT GREEN (-1450 3500);
DISPLAY INVISIBLE (-1450 3500);
FORCEPROP 1 LAST COMMENT_BODY TRUE
J 0
(-1820 3530);
DISPLAY 1.170213 (-1820 3530);
PAINT GREEN (-1820 3530);
DISPLAY INVISIBLE (-1820 3530);
FORCEPROP 2 LAST PATH I85
J 0
(-1600 3700);
DISPLAY 1.021277 (-1600 3700);
PAINT ORANGE (-1600 3700);
DISPLAY INVISIBLE (-1600 3700);
FORCEADD SKX_EXT_B..14
(-4100 2575);
FORCEPROP 1 LAST LOCATION U5D1
J 0
(-4850 3825);
DISPLAY 0.617021 (-4850 3825);
PAINT AQUA (-4850 3825);
FORCEPROP 1 LAST PART_NUMBER TBD
J 0
(-4850 1375);
DISPLAY 0.617021 (-4850 1375);
PAINT BLUE (-4850 1375);
FORCEPROP 1 LAST MATERIAL IC
J 0
(-4850 3775);
DISPLAY 0.617021 (-4850 3775);
PAINT SKYBLUE (-4850 3775);
FORCEPROP 2 LASTPIN (-3300 3575) $PN K21
J 0
(-3290 3585);
DISPLAY 0.617021 (-3290 3585);
PAINT ORANGE (-3290 3585);
FORCEPROP 2 LASTPIN (-3300 3525) $PN G20
J 0
(-3290 3535);
DISPLAY 0.617021 (-3290 3535);
PAINT ORANGE (-3290 3535);
FORCEPROP 2 LASTPIN (-3300 3475) $PN H19
J 0
(-3290 3485);
DISPLAY 0.617021 (-3290 3485);
PAINT ORANGE (-3290 3485);
FORCEPROP 2 LASTPIN (-3300 3425) $PN J18
J 0
(-3290 3435);
DISPLAY 0.617021 (-3290 3435);
PAINT ORANGE (-3290 3435);
FORCEPROP 2 LASTPIN (-3300 3375) $PN L18
J 0
(-3290 3385);
DISPLAY 0.617021 (-3290 3385);
PAINT ORANGE (-3290 3385);
FORCEPROP 2 LASTPIN (-3300 3325) $PN G16
J 0
(-3290 3335);
DISPLAY 0.617021 (-3290 3335);
PAINT ORANGE (-3290 3335);
FORCEPROP 2 LASTPIN (-3300 3275) $PN H15
J 0
(-3290 3285);
DISPLAY 0.617021 (-3290 3285);
PAINT ORANGE (-3290 3285);
FORCEPROP 2 LASTPIN (-3300 3225) $PN E14
J 0
(-3290 3235);
DISPLAY 0.617021 (-3290 3235);
PAINT ORANGE (-3290 3235);
FORCEPROP 2 LASTPIN (-3300 3175) $PN F13
J 0
(-3290 3185);
DISPLAY 0.617021 (-3290 3185);
PAINT ORANGE (-3290 3185);
FORCEPROP 2 LASTPIN (-3300 3125) $PN G12
J 0
(-3290 3135);
DISPLAY 0.617021 (-3290 3135);
PAINT ORANGE (-3290 3135);
FORCEPROP 2 LASTPIN (-3300 3075) $PN H9
J 0
(-3290 3085);
DISPLAY 0.617021 (-3290 3085);
PAINT ORANGE (-3290 3085);
FORCEPROP 2 LASTPIN (-3300 3025) $PN E10
J 0
(-3290 3035);
DISPLAY 0.617021 (-3290 3035);
PAINT ORANGE (-3290 3035);
FORCEPROP 2 LASTPIN (-3300 2975) $PN F9
J 0
(-3290 2985);
DISPLAY 0.617021 (-3290 2985);
PAINT ORANGE (-3290 2985);
FORCEPROP 2 LASTPIN (-3300 2925) $PN J8
J 0
(-3290 2935);
DISPLAY 0.617021 (-3290 2935);
PAINT ORANGE (-3290 2935);
FORCEPROP 2 LASTPIN (-3300 2875) $PN K7
J 0
(-3290 2885);
DISPLAY 0.617021 (-3290 2885);
PAINT ORANGE (-3290 2885);
FORCEPROP 2 LASTPIN (-3300 2825) $PN F7
J 0
(-3290 2835);
DISPLAY 0.617021 (-3290 2835);
PAINT ORANGE (-3290 2835);
FORCEPROP 2 LASTPIN (-3300 2775) $PN H5
J 0
(-3290 2785);
DISPLAY 0.617021 (-3290 2785);
PAINT ORANGE (-3290 2785);
FORCEPROP 2 LASTPIN (-3300 2725) $PN M5
J 0
(-3290 2735);
DISPLAY 0.617021 (-3290 2735);
PAINT ORANGE (-3290 2735);
FORCEPROP 2 LASTPIN (-3300 2675) $PN K3
J 0
(-3290 2685);
DISPLAY 0.617021 (-3290 2685);
PAINT ORANGE (-3290 2685);
FORCEPROP 2 LASTPIN (-3300 2625) $PN P3
J 0
(-3290 2635);
DISPLAY 0.617021 (-3290 2635);
PAINT ORANGE (-3290 2635);
FORCEPROP 2 LASTPIN (-3300 2525) $PN H21
J 0
(-3290 2535);
DISPLAY 0.617021 (-3290 2535);
PAINT ORANGE (-3290 2535);
FORCEPROP 2 LASTPIN (-3300 2475) $PN F21
J 0
(-3290 2485);
DISPLAY 0.617021 (-3290 2485);
PAINT ORANGE (-3290 2485);
FORCEPROP 2 LASTPIN (-3300 2425) $PN J20
J 0
(-3290 2435);
DISPLAY 0.617021 (-3290 2435);
PAINT ORANGE (-3290 2435);
FORCEPROP 2 LASTPIN (-3300 2375) $PN G18
J 0
(-3290 2385);
DISPLAY 0.617021 (-3290 2385);
PAINT ORANGE (-3290 2385);
FORCEPROP 2 LASTPIN (-3300 2325) $PN K19
J 0
(-3290 2335);
DISPLAY 0.617021 (-3290 2335);
PAINT ORANGE (-3290 2335);
FORCEPROP 2 LASTPIN (-3300 2275) $PN H17
J 0
(-3290 2285);
DISPLAY 0.617021 (-3290 2285);
PAINT ORANGE (-3290 2285);
FORCEPROP 2 LASTPIN (-3300 2225) $PN F15
J 0
(-3290 2235);
DISPLAY 0.617021 (-3290 2235);
PAINT ORANGE (-3290 2235);
FORCEPROP 2 LASTPIN (-3300 2175) $PN D15
J 0
(-3290 2185);
DISPLAY 0.617021 (-3290 2185);
PAINT ORANGE (-3290 2185);
FORCEPROP 2 LASTPIN (-3300 2125) $PN G14
J 0
(-3290 2135);
DISPLAY 0.617021 (-3290 2135);
PAINT ORANGE (-3290 2135);
FORCEPROP 2 LASTPIN (-3300 2075) $PN E12
J 0
(-3290 2085);
DISPLAY 0.617021 (-3290 2085);
PAINT ORANGE (-3290 2085);
FORCEPROP 2 LASTPIN (-3300 2025) $PN G10
J 0
(-3290 2035);
DISPLAY 0.617021 (-3290 2035);
PAINT ORANGE (-3290 2035);
FORCEPROP 2 LASTPIN (-3300 1975) $PN F11
J 0
(-3290 1985);
DISPLAY 0.617021 (-3290 1985);
PAINT ORANGE (-3290 1985);
FORCEPROP 2 LASTPIN (-3300 1925) $PN D9
J 0
(-3290 1935);
DISPLAY 0.617021 (-3290 1935);
PAINT ORANGE (-3290 1935);
FORCEPROP 2 LASTPIN (-3300 1875) $PN K9
J 0
(-3290 1885);
DISPLAY 0.617021 (-3290 1885);
PAINT ORANGE (-3290 1885);
FORCEPROP 2 LASTPIN (-3300 1825) $PN H7
J 0
(-3290 1835);
DISPLAY 0.617021 (-3290 1835);
PAINT ORANGE (-3290 1835);
FORCEPROP 2 LASTPIN (-3300 1775) $PN G6
J 0
(-3290 1785);
DISPLAY 0.617021 (-3290 1785);
PAINT ORANGE (-3290 1785);
FORCEPROP 2 LASTPIN (-3300 1725) $PN J6
J 0
(-3290 1735);
DISPLAY 0.617021 (-3290 1735);
PAINT ORANGE (-3290 1735);
FORCEPROP 2 LASTPIN (-3300 1675) $PN K5
J 0
(-3290 1685);
DISPLAY 0.617021 (-3290 1685);
PAINT ORANGE (-3290 1685);
FORCEPROP 2 LASTPIN (-3300 1625) $PN L4
J 0
(-3290 1635);
DISPLAY 0.617021 (-3290 1635);
PAINT ORANGE (-3290 1635);
FORCEPROP 2 LASTPIN (-3300 1575) $PN M3
J 0
(-3290 1585);
DISPLAY 0.617021 (-3290 1585);
PAINT ORANGE (-3290 1585);
FORCEPROP 2 LASTPIN (-4900 3575) $PN AA20
J 2
(-4910 3585);
DISPLAY 0.617021 (-4910 3585);
PAINT ORANGE (-4910 3585);
FORCEPROP 2 LASTPIN (-4900 3525) $PN W20
J 2
(-4910 3535);
DISPLAY 0.617021 (-4910 3535);
PAINT ORANGE (-4910 3535);
FORCEPROP 2 LASTPIN (-4900 3475) $PN Y19
J 2
(-4910 3485);
DISPLAY 0.617021 (-4910 3485);
PAINT ORANGE (-4910 3485);
FORCEPROP 2 LASTPIN (-4900 3425) $PN T21
J 2
(-4910 3435);
DISPLAY 0.617021 (-4910 3435);
PAINT ORANGE (-4910 3435);
FORCEPROP 2 LASTPIN (-4900 3375) $PN T19
J 2
(-4910 3385);
DISPLAY 0.617021 (-4910 3385);
PAINT ORANGE (-4910 3385);
FORCEPROP 2 LASTPIN (-4900 3325) $PN P19
J 2
(-4910 3335);
DISPLAY 0.617021 (-4910 3335);
PAINT ORANGE (-4910 3335);
FORCEPROP 2 LASTPIN (-4900 3275) $PN V17
J 2
(-4910 3285);
DISPLAY 0.617021 (-4910 3285);
PAINT ORANGE (-4910 3285);
FORCEPROP 2 LASTPIN (-4900 3225) $PN W16
J 2
(-4910 3235);
DISPLAY 0.617021 (-4910 3235);
PAINT ORANGE (-4910 3235);
FORCEPROP 2 LASTPIN (-4900 3175) $PN N16
J 2
(-4910 3185);
DISPLAY 0.617021 (-4910 3185);
PAINT ORANGE (-4910 3185);
FORCEPROP 2 LASTPIN (-4900 3125) $PN T15
J 2
(-4910 3135);
DISPLAY 0.617021 (-4910 3135);
PAINT ORANGE (-4910 3135);
FORCEPROP 2 LASTPIN (-4900 3075) $PN P13
J 2
(-4910 3085);
DISPLAY 0.617021 (-4910 3085);
PAINT ORANGE (-4910 3085);
FORCEPROP 2 LASTPIN (-4900 3025) $PN M13
J 2
(-4910 3035);
DISPLAY 0.617021 (-4910 3035);
PAINT ORANGE (-4910 3035);
FORCEPROP 2 LASTPIN (-4900 2975) $PN N12
J 2
(-4910 2985);
DISPLAY 0.617021 (-4910 2985);
PAINT ORANGE (-4910 2985);
FORCEPROP 2 LASTPIN (-4900 2925) $PN T11
J 2
(-4910 2935);
DISPLAY 0.617021 (-4910 2935);
PAINT ORANGE (-4910 2935);
FORCEPROP 2 LASTPIN (-4900 2875) $PN U10
J 2
(-4910 2885);
DISPLAY 0.617021 (-4910 2885);
PAINT ORANGE (-4910 2885);
FORCEPROP 2 LASTPIN (-4900 2825) $PN N10
J 2
(-4910 2835);
DISPLAY 0.617021 (-4910 2835);
PAINT ORANGE (-4910 2835);
FORCEPROP 2 LASTPIN (-4900 2775) $PN R8
J 2
(-4910 2785);
DISPLAY 0.617021 (-4910 2785);
PAINT ORANGE (-4910 2785);
FORCEPROP 2 LASTPIN (-4900 2725) $PN U8
J 2
(-4910 2735);
DISPLAY 0.617021 (-4910 2735);
PAINT ORANGE (-4910 2735);
FORCEPROP 2 LASTPIN (-4900 2675) $PN T7
J 2
(-4910 2685);
DISPLAY 0.617021 (-4910 2685);
PAINT ORANGE (-4910 2685);
FORCEPROP 2 LASTPIN (-4900 2625) $PN R6
J 2
(-4910 2635);
DISPLAY 0.617021 (-4910 2635);
PAINT ORANGE (-4910 2635);
FORCEPROP 2 LASTPIN (-4900 2525) $PN AB19
J 2
(-4910 2535);
DISPLAY 0.617021 (-4910 2535);
PAINT ORANGE (-4910 2535);
FORCEPROP 2 LASTPIN (-4900 2475) $PN Y21
J 2
(-4910 2485);
DISPLAY 0.617021 (-4910 2485);
PAINT ORANGE (-4910 2485);
FORCEPROP 2 LASTPIN (-4900 2425) $PN V19
J 2
(-4910 2435);
DISPLAY 0.617021 (-4910 2435);
PAINT ORANGE (-4910 2435);
FORCEPROP 2 LASTPIN (-4900 2375) $PN P21
J 2
(-4910 2385);
DISPLAY 0.617021 (-4910 2385);
PAINT ORANGE (-4910 2385);
FORCEPROP 2 LASTPIN (-4900 2325) $PN U18
J 2
(-4910 2335);
DISPLAY 0.617021 (-4910 2335);
PAINT ORANGE (-4910 2335);
FORCEPROP 2 LASTPIN (-4900 2275) $PN R20
J 2
(-4910 2285);
DISPLAY 0.617021 (-4910 2285);
PAINT ORANGE (-4910 2285);
FORCEPROP 2 LASTPIN (-4900 2225) $PN W18
J 2
(-4910 2235);
DISPLAY 0.617021 (-4910 2235);
PAINT ORANGE (-4910 2235);
FORCEPROP 2 LASTPIN (-4900 2175) $PN U16
J 2
(-4910 2185);
DISPLAY 0.617021 (-4910 2185);
PAINT ORANGE (-4910 2185);
FORCEPROP 2 LASTPIN (-4900 2125) $PN P17
J 2
(-4910 2135);
DISPLAY 0.617021 (-4910 2135);
PAINT ORANGE (-4910 2135);
FORCEPROP 2 LASTPIN (-4900 2075) $PN R16
J 2
(-4910 2085);
DISPLAY 0.617021 (-4910 2085);
PAINT ORANGE (-4910 2085);
FORCEPROP 2 LASTPIN (-4900 2025) $PN R12
J 2
(-4910 2035);
DISPLAY 0.617021 (-4910 2035);
PAINT ORANGE (-4910 2035);
FORCEPROP 2 LASTPIN (-4900 1975) $PN N14
J 2
(-4910 1985);
DISPLAY 0.617021 (-4910 1985);
PAINT ORANGE (-4910 1985);
FORCEPROP 2 LASTPIN (-4900 1925) $PN L12
J 2
(-4910 1935);
DISPLAY 0.617021 (-4910 1935);
PAINT ORANGE (-4910 1935);
FORCEPROP 2 LASTPIN (-4900 1875) $PN U12
J 2
(-4910 1885);
DISPLAY 0.617021 (-4910 1885);
PAINT ORANGE (-4910 1885);
FORCEPROP 2 LASTPIN (-4900 1825) $PN R10
J 2
(-4910 1835);
DISPLAY 0.617021 (-4910 1835);
PAINT ORANGE (-4910 1835);
FORCEPROP 2 LASTPIN (-4900 1775) $PN P9
J 2
(-4910 1785);
DISPLAY 0.617021 (-4910 1785);
PAINT ORANGE (-4910 1785);
FORCEPROP 2 LASTPIN (-4900 1725) $PN T9
J 2
(-4910 1735);
DISPLAY 0.617021 (-4910 1735);
PAINT ORANGE (-4910 1735);
FORCEPROP 2 LASTPIN (-4900 1675) $PN V7
J 2
(-4910 1685);
DISPLAY 0.617021 (-4910 1685);
PAINT ORANGE (-4910 1685);
FORCEPROP 2 LASTPIN (-4900 1625) $PN P7
J 2
(-4910 1635);
DISPLAY 0.617021 (-4910 1635);
PAINT ORANGE (-4910 1635);
FORCEPROP 2 LASTPIN (-4900 1575) $PN T5
J 2
(-4910 1585);
DISPLAY 0.617021 (-4910 1585);
PAINT ORANGE (-4910 1585);
FORCEPROP 1 LAST PACK_TYPE BGA1
J 0
(-4850 3875);
PAINT SKYBLUE (-4850 3875);
DISPLAY INVISIBLE (-4850 3875);
FORCEPROP 2 LAST CDS_LIB chpset_lib
J 0
(-4100 2575);
PAINT ORANGE (-4100 2575);
DISPLAY INVISIBLE (-4100 2575);
FORCEPROP 2 LAST SEC_TYPE BGA1
J 0
(-4850 3875);
DISPLAY 1.021277 (-4850 3875);
PAINT ORANGE (-4850 3875);
DISPLAY INVISIBLE (-4850 3875);
FORCEPROP 2 LAST SEC 14
J 0
(-4850 3875);
DISPLAY 0.680851 (-4850 3875);
PAINT MONO (-4850 3875);
DISPLAY INVISIBLE (-4850 3875);
FORCEPROP 2 LAST CDS_LOCATION U5D1
J 0
(-4850 3825);
DISPLAY 0.617021 (-4850 3825);
PAINT AQUA (-4850 3825);
DISPLAY INVISIBLE (-4850 3825);
FORCEPROP 1 LAST PATH I86
J 0
(-4100 3775);
PAINT GREEN (-4100 3775);
DISPLAY INVISIBLE (-4100 3775);
FORCEPROP 0 LAST ROOM CPU0
J 0
(-4850 3925);
DISPLAY 1.021277 (-4850 3925);
PAINT ORANGE (-4850 3925);
DISPLAY INVISIBLE (-4850 3925);
FORCEADD TAP..1
R 2
(-5300 1875);
FORCEPROP 3 LASTPIN (-5250 1875) SIG_NAME UPI_CPU1_CPU0_P1P1_DN<13>
J 0
(-5240 1885);
DISPLAY 0.659574 (-5240 1885);
PAINT MONO (-5240 1885);
DISPLAY INVISIBLE (-5240 1885);
FORCEPROP 1 LASTPIN (-5250 1875) BN 13
J 2
(-5238 1883);
DISPLAY 0.617021 (-5238 1883);
PAINT PINK (-5238 1883);
FORCEPROP 2 LAST CDS_LIB mstr_standard
J 0
(-5300 1875);
PAINT MONO (-5300 1875);
DISPLAY INVISIBLE (-5300 1875);
FORCEPROP 1 LAST BODY_TYPE PLUMBING
J 2
(-5300 1925);
DISPLAY 1.446809 (-5300 1925);
PAINT GREEN (-5300 1925);
DISPLAY INVISIBLE (-5300 1925);
FORCEPROP 1 LAST HDL_TAP TRUE
J 2
(-5625 1750);
DISPLAY 1.446809 (-5625 1750);
PAINT GREEN (-5625 1750);
DISPLAY INVISIBLE (-5625 1750);
FORCEPROP 1 LAST PATH I9
J 2
(-5298 1875);
DISPLAY 0.872340 (-5298 1875);
PAINT GREEN (-5298 1875);
DISPLAY INVISIBLE (-5298 1875);
FORCEADD PRELIM..10
(-4115 2565);
PAINT GRAY (-4115 2565);
FORCEPROP 2 LAST CDS_LIB mstr_misc
J 0
(-4115 2565);
PAINT ORANGE (-4115 2565);
DISPLAY INVISIBLE (-4115 2565);
FORCEPROP 1 LAST COMMENT_BODY TRUE
J 0
(-4115 2565);
PAINT ORANGE (-4115 2565);
DISPLAY INVISIBLE (-4115 2565);
FORCEADD DESIGN_NOTE..1
(-4675 1300);
FORCEPROP 0 LAST L1 CPU SYMBOLS 1-30 ARE PRELIMINARY AND SUBJECT TO CHANGE
J 0
(-4875 1175);
DISPLAY 1.021277 (-4875 1175);
PAINT ORANGE (-4875 1175);
FORCEPROP 2 LAST CDS_LIB mstr_symbols
J 0
(-4675 1300);
PAINT ORANGE (-4675 1300);
DISPLAY INVISIBLE (-4675 1300);
FORCEPROP 1 LAST COMMENT_BODY TRUE
J 0
(-4650 1400);
DISPLAY 0.978723 (-4650 1400);
PAINT ORANGE (-4650 1400);
DISPLAY INVISIBLE (-4650 1400);
FORCEADD INTEL_CORP_BPAGE..1
(0 0);
FORCEPROP 1 LAST CDS_CON_LAST_MODIFIED Tue Dec 01 11:51:22 2015
J 0
(-1425 325);
DISPLAY 1.340426 (-1425 325);
PAINT GREEN (-1425 325);
DISPLAY INVISIBLE (-1425 325);
FORCEPROP 1 LAST CUSTOM_TXT_CDS <CURRENT_DESIGN_SHEET> OF <TOTAL_DESIGN_SHEETS>
J 0
(-500 25);
PAINT GREEN (-500 25);
FORCEPROP 1 LAST CUSTOM_TXT_CDS <CON_LAST_MODIFIED>
J 0
(-1925 350);
PAINT GREEN (-1925 350);
FORCEPROP 2 LAST CUSTOM_TXT_CDS <XR_PAGE_TITLE>
J 0
(-7890 5250);
DISPLAY 0.638298 (-7890 5250);
PAINT PINK (-7890 5250);
DISPLAY INVISIBLE (-7890 5250);
FORCEPROP 1 LAST SCH_ADDRESS3 Santa Clara, CA 95052-8119
J 0
(-3975 25);
DISPLAY 0.617021 (-3975 25);
PAINT GREEN (-3975 25);
FORCEPROP 1 LAST SCH_ADDRESS2 P.O. BOX 58119
J 0
(-3975 75);
DISPLAY 0.617021 (-3975 75);
PAINT GREEN (-3975 75);
FORCEPROP 1 LAST SCH_ADDRESS1 2200 Mission College Blvd.
J 0
(-3975 125);
DISPLAY 0.617021 (-3975 125);
PAINT GREEN (-3975 125);
FORCEPROP 1 LAST SCH_TITLE SKYLAKE - SKT0 - 14 OF 21
J 0
(-7950 50);
DISPLAY 1.212766 (-7950 50);
PAINT GREEN (-7950 50);
FORCEPROP 1 LAST SCH_NUMBER H4694802
J 0
(-1300 150);
DISPLAY 1.212766 (-1300 150);
PAINT YELLOW (-1300 150);
FORCEPROP 1 LAST SCH_DEPT BESD
J 1
(-4450 100);
DISPLAY 1.212766 (-4450 100);
PAINT YELLOW (-4450 100);
FORCEPROP 1 LAST SCH_REV 2.420
J 0
(-250 150);
DISPLAY 0.978723 (-250 150);
PAINT YELLOW (-250 150);
FORCEPROP 2 LAST PAGE_BORDER TRUE
J 0
(-7890 5250);
DISPLAY 0.851064 (-7890 5250);
PAINT PINK (-7890 5250);
DISPLAY INVISIBLE (-7890 5250);
FORCEPROP 2 LAST CDS_LIB mstr_symbols
J 0
(0 0);
PAINT ORANGE (0 0);
DISPLAY INVISIBLE (0 0);
FORCEPROP 1 LAST COMMENT_BODY TRUE
J 0
(12 12);
DISPLAY 0.638298 (12 12);
PAINT GREEN (12 12);
DISPLAY INVISIBLE (12 12);
FORCEPROP 2 LAST CDS_XR_PAGE_TITLE CR-34 : @BASEBOARD_FAB2_LIB.BASEBOARD_FAB2(SCH_1):PAGE34
J 0
(-7890 5250);
DISPLAY 0.638298 (-7890 5250);
PAINT PINK (-7890 5250);
DISPLAY INVISIBLE (-7890 5250);
WIRE 17 -1 (-2925 2575)(-2925 2550);
WIRE 17 -1 (-2925 2575)(-1825 2575);
FORCEPROP 2 LAST SIG_NAME UPI_CPU0_CPU1_P1P1_DN<19..0>
J 0
(-2835 2585);
DISPLAY 0.617021 (-2835 2585);
PAINT ORANGE (-2835 2585);
WIRE 17 -1 (-2925 2550)(-2925 2500);
WIRE 17 -1 (-2925 2500)(-2925 2450);
WIRE 17 -1 (-2925 2450)(-2925 2400);
WIRE 17 -1 (-2925 2400)(-2925 2350);
WIRE 17 -1 (-2925 2350)(-2925 2300);
WIRE 17 -1 (-2925 2300)(-2925 2250);
WIRE 17 -1 (-2925 2250)(-2925 2200);
WIRE 17 -1 (-2925 2200)(-2925 2150);
WIRE 17 -1 (-2925 2150)(-2925 2100);
WIRE 17 -1 (-2925 2100)(-2925 2050);
WIRE 17 -1 (-2925 2050)(-2925 2000);
WIRE 17 -1 (-2925 2000)(-2925 1950);
WIRE 17 -1 (-2925 1950)(-2925 1900);
WIRE 17 -1 (-2925 1900)(-2925 1850);
WIRE 17 -1 (-2925 1850)(-2925 1800);
WIRE 17 -1 (-2925 1800)(-2925 1750);
WIRE 17 -1 (-2925 1750)(-2925 1700);
WIRE 17 -1 (-2925 1700)(-2925 1650);
WIRE 17 -1 (-2925 1650)(-2925 1600);
WIRE 17 -1 (-2925 3625)(-2925 3600);
WIRE 17 -1 (-2925 3625)(-1825 3625);
FORCEPROP 2 LAST SIG_NAME UPI_CPU0_CPU1_P1P1_DP<19..0>
J 0
(-2835 3635);
DISPLAY 0.617021 (-2835 3635);
PAINT ORANGE (-2835 3635);
WIRE 17 -1 (-2925 3600)(-2925 3550);
WIRE 17 -1 (-2925 3550)(-2925 3500);
WIRE 17 -1 (-2925 3500)(-2925 3450);
WIRE 17 -1 (-2925 3450)(-2925 3400);
WIRE 17 -1 (-2925 3400)(-2925 3350);
WIRE 17 -1 (-2925 3350)(-2925 3300);
WIRE 17 -1 (-2925 3300)(-2925 3250);
WIRE 17 -1 (-2925 3250)(-2925 3200);
WIRE 17 -1 (-2925 3200)(-2925 3150);
WIRE 17 -1 (-2925 3150)(-2925 3100);
WIRE 17 -1 (-2925 3100)(-2925 3050);
WIRE 17 -1 (-2925 3050)(-2925 3000);
WIRE 17 -1 (-2925 3000)(-2925 2950);
WIRE 17 -1 (-2925 2950)(-2925 2900);
WIRE 17 -1 (-2925 2900)(-2925 2850);
WIRE 17 -1 (-2925 2850)(-2925 2800);
WIRE 17 -1 (-2925 2800)(-2925 2750);
WIRE 17 -1 (-2925 2750)(-2925 2700);
WIRE 17 -1 (-2925 2700)(-2925 2650);
WIRE 17 -1 (-5350 2500)(-5350 2550);
WIRE 17 -1 (-5350 2450)(-5350 2500);
WIRE 17 -1 (-5350 2550)(-5350 2575);
WIRE 17 -1 (-6450 2575)(-5350 2575);
FORCEPROP 2 LAST SIG_NAME UPI_CPU1_CPU0_P1P1_DN<19..0>
J 0
(-6385 2585);
DISPLAY 0.617021 (-6385 2585);
PAINT ORANGE (-6385 2585);
WIRE 17 -1 (-5350 2450)(-5350 2400);
WIRE 17 -1 (-5350 2400)(-5350 2350);
WIRE 17 -1 (-5350 2350)(-5350 2300);
WIRE 17 -1 (-5350 2300)(-5350 2250);
WIRE 17 -1 (-5350 2250)(-5350 2200);
WIRE 17 -1 (-5350 2200)(-5350 2150);
WIRE 17 -1 (-5350 2150)(-5350 2100);
WIRE 17 -1 (-5350 2100)(-5350 2050);
WIRE 17 -1 (-5350 2050)(-5350 2000);
WIRE 17 -1 (-5350 2000)(-5350 1950);
WIRE 17 -1 (-5350 1950)(-5350 1900);
WIRE 17 -1 (-5350 1900)(-5350 1850);
WIRE 17 -1 (-5350 1850)(-5350 1800);
WIRE 17 -1 (-5350 1800)(-5350 1750);
WIRE 17 -1 (-5350 1750)(-5350 1700);
WIRE 17 -1 (-5350 1650)(-5350 1700);
WIRE 17 -1 (-5350 1600)(-5350 1650);
WIRE 17 -1 (-5350 3550)(-5350 3600);
WIRE 17 -1 (-5350 3500)(-5350 3550);
WIRE 17 -1 (-5350 3625)(-5350 3600);
WIRE 17 -1 (-6450 3625)(-5350 3625);
FORCEPROP 2 LAST SIG_NAME UPI_CPU1_CPU0_P1P1_DP<19..0>
J 0
(-6360 3635);
DISPLAY 0.617021 (-6360 3635);
PAINT ORANGE (-6360 3635);
WIRE 17 -1 (-5350 3500)(-5350 3450);
WIRE 17 -1 (-5350 3450)(-5350 3400);
WIRE 17 -1 (-5350 3400)(-5350 3350);
WIRE 17 -1 (-5350 3350)(-5350 3300);
WIRE 17 -1 (-5350 3300)(-5350 3250);
WIRE 17 -1 (-5350 3250)(-5350 3200);
WIRE 17 -1 (-5350 3200)(-5350 3150);
WIRE 17 -1 (-5350 3150)(-5350 3100);
WIRE 17 -1 (-5350 3100)(-5350 3050);
WIRE 17 -1 (-5350 3050)(-5350 3000);
WIRE 17 -1 (-5350 3000)(-5350 2950);
WIRE 17 -1 (-5350 2950)(-5350 2900);
WIRE 17 -1 (-5350 2900)(-5350 2850);
WIRE 17 -1 (-5350 2850)(-5350 2800);
WIRE 17 -1 (-5350 2800)(-5350 2750);
WIRE 17 -1 (-5350 2700)(-5350 2750);
WIRE 17 -1 (-5350 2650)(-5350 2700);
WIRE 16 -1 (-5250 1575)(-4900 1575);
WIRE 16 -1 (-5250 1625)(-4900 1625);
WIRE 16 -1 (-5250 1675)(-4900 1675);
WIRE 16 -1 (-5250 1725)(-4900 1725);
WIRE 16 -1 (-5250 1775)(-4900 1775);
WIRE 16 -1 (-5250 1825)(-4900 1825);
WIRE 16 -1 (-5250 1875)(-4900 1875);
WIRE 16 -1 (-5250 1925)(-4900 1925);
WIRE 16 -1 (-5250 1975)(-4900 1975);
WIRE 16 -1 (-5250 2025)(-4900 2025);
WIRE 16 -1 (-5250 2625)(-4900 2625);
WIRE 16 -1 (-5250 2675)(-4900 2675);
WIRE 16 -1 (-5250 2725)(-4900 2725);
WIRE 16 -1 (-5250 2775)(-4900 2775);
WIRE 16 -1 (-5250 2825)(-4900 2825);
WIRE 16 -1 (-5250 2875)(-4900 2875);
WIRE 16 -1 (-5250 2925)(-4900 2925);
WIRE 16 -1 (-5250 2975)(-4900 2975);
WIRE 16 -1 (-5250 3025)(-4900 3025);
WIRE 16 -1 (-5250 3075)(-4900 3075);
WIRE 16 -1 (-5250 3125)(-4900 3125);
WIRE 16 -1 (-5250 3175)(-4900 3175);
WIRE 16 -1 (-5250 3225)(-4900 3225);
WIRE 16 -1 (-5250 3275)(-4900 3275);
WIRE 16 -1 (-5250 3325)(-4900 3325);
WIRE 16 -1 (-5250 3375)(-4900 3375);
WIRE 16 -1 (-5250 3425)(-4900 3425);
WIRE 16 -1 (-5250 3475)(-4900 3475);
WIRE 16 -1 (-5250 3525)(-4900 3525);
WIRE 16 -1 (-5250 3575)(-4900 3575);
WIRE 16 -1 (-5250 2075)(-4900 2075);
WIRE 16 -1 (-5250 2125)(-4900 2125);
WIRE 16 -1 (-5250 2175)(-4900 2175);
WIRE 16 -1 (-5250 2225)(-4900 2225);
WIRE 16 -1 (-5250 2275)(-4900 2275);
WIRE 16 -1 (-5250 2325)(-4900 2325);
WIRE 16 -1 (-5250 2375)(-4900 2375);
WIRE 16 -1 (-5250 2425)(-4900 2425);
WIRE 16 -1 (-5250 2475)(-4900 2475);
WIRE 16 -1 (-5250 2525)(-4900 2525);
WIRE 16 -1 (-3025 1575)(-3300 1575);
WIRE 16 -1 (-3025 1625)(-3300 1625);
WIRE 16 -1 (-3025 1675)(-3300 1675);
WIRE 16 -1 (-3025 1725)(-3300 1725);
WIRE 16 -1 (-3300 1775)(-3025 1775);
WIRE 16 -1 (-3025 1825)(-3300 1825);
WIRE 16 -1 (-3300 1875)(-3025 1875);
WIRE 16 -1 (-3025 1925)(-3300 1925);
WIRE 16 -1 (-3025 1975)(-3300 1975);
WIRE 16 -1 (-3025 2025)(-3300 2025);
WIRE 16 -1 (-3025 2625)(-3300 2625);
WIRE 16 -1 (-3025 2675)(-3300 2675);
WIRE 16 -1 (-3300 2725)(-3025 2725);
WIRE 16 -1 (-3025 2775)(-3300 2775);
WIRE 16 -1 (-3025 2825)(-3300 2825);
WIRE 16 -1 (-3025 2875)(-3300 2875);
WIRE 16 -1 (-3025 2925)(-3300 2925);
WIRE 16 -1 (-3025 2975)(-3300 2975);
WIRE 16 -1 (-3300 3025)(-3025 3025);
WIRE 16 -1 (-3025 3075)(-3300 3075);
WIRE 16 -1 (-3025 3125)(-3300 3125);
WIRE 16 -1 (-3025 3175)(-3300 3175);
WIRE 16 -1 (-3025 3225)(-3300 3225);
WIRE 16 -1 (-3025 3275)(-3300 3275);
WIRE 16 -1 (-3300 3325)(-3025 3325);
WIRE 16 -1 (-3300 3375)(-3025 3375);
WIRE 16 -1 (-3025 3425)(-3300 3425);
WIRE 16 -1 (-3025 3475)(-3300 3475);
WIRE 16 -1 (-3025 3525)(-3300 3525);
WIRE 16 -1 (-3025 3575)(-3300 3575);
WIRE 16 -1 (-3025 2075)(-3300 2075);
WIRE 16 -1 (-3300 2125)(-3025 2125);
WIRE 16 -1 (-3300 2175)(-3025 2175);
WIRE 16 -1 (-3025 2225)(-3300 2225);
WIRE 16 -1 (-3025 2275)(-3300 2275);
WIRE 16 -1 (-3025 2325)(-3300 2325);
WIRE 16 -1 (-3025 2375)(-3300 2375);
WIRE 16 -1 (-3025 2425)(-3300 2425);
WIRE 16 -1 (-3025 2475)(-3300 2475);
WIRE 16 -1 (-3025 2525)(-3300 2525);
FORCENOTE
ROOM=CPU0
(-7925 375) 0;
DISPLAY LEFT (-7925 375);
DISPLAY 1.723404 (-7925 375);
PAINT PURPLE (-7925 375);
FORCENOTE
BOM_COST=PROC_SOCKET
(-7925 250) 0;
DISPLAY LEFT (-7925 250);
DISPLAY 1.723404 (-7925 250);
PAINT PURPLE (-7925 250);
QUIT
